(kicad_sch
	(version 20250114)
	(generator "eeschema")
	(generator_version "9.0")
	(paper "A3")
	(title_block
		(title "RDIMM DDR5 Tester")
		(date "2026-05-21")
		(rev "2.2.0")
		(company "Antmicro")
		(comment 1 "www.antmicro.com")
		(comment 2 "Antmicro")
	)
	(text "+1V2"
		(exclude_from_sim no)
		(at 153.67 138.43 0)
		(effects
			(font
				(size 1.27 1.27)
			)
			(justify left bottom)
		)
	)
	(text "1"
		(exclude_from_sim no)
		(at 175.26 128.27 0)
		(effects
			(font
				(size 1.27 1.27)
			)
			(justify left bottom)
		)
	)
	(text "+3V3"
		(exclude_from_sim no)
		(at 153.67 130.81 0)
		(effects
			(font
				(size 1.27 1.27)
			)
			(justify left bottom)
		)
	)
	(text "1"
		(exclude_from_sim no)
		(at 171.45 128.27 0)
		(effects
			(font
				(size 1.27 1.27)
			)
			(justify left bottom)
		)
	)
	(text "X"
		(exclude_from_sim no)
		(at 175.26 133.35 0)
		(effects
			(font
				(size 1.27 1.27)
			)
			(justify left bottom)
		)
	)
	(text "Current sense monitor"
		(exclude_from_sim no)
		(at 16.51 171.45 0)
		(effects
			(font
				(size 2 2)
				(thickness 0.6)
				(bold yes)
			)
			(justify left bottom)
		)
	)
	(text "DC-DC IO"
		(exclude_from_sim no)
		(at 15.24 20.32 0)
		(effects
			(font
				(size 3 3)
				(thickness 0.6)
				(bold yes)
			)
			(justify left bottom)
		)
	)
	(text "1"
		(exclude_from_sim no)
		(at 163.83 128.27 0)
		(effects
			(font
				(size 1.27 1.27)
			)
			(justify left bottom)
		)
	)
	(text "X"
		(exclude_from_sim no)
		(at 163.83 130.81 0)
		(effects
			(font
				(size 1.27 1.27)
			)
			(justify left bottom)
		)
	)
	(text "VDDQ"
		(exclude_from_sim no)
		(at 153.67 135.89 0)
		(effects
			(font
				(size 1.27 1.27)
			)
			(justify left bottom)
		)
	)
	(text "As both MPM54304GMN have same \naddress (from factory), there is \na need to cut SCL signals\nusing dip switch"
		(exclude_from_sim no)
		(at 97.79 100.33 0)
		(effects
			(font
				(size 1.27 1.27)
			)
			(justify left bottom)
		)
	)
	(text "NOTE:\noptional \nexternal divider "
		(exclude_from_sim no)
		(at 321.945 112.395 0)
		(effects
			(font
				(size 1.27 1.27)
			)
			(justify left bottom)
		)
	)
	(text "+5V"
		(exclude_from_sim no)
		(at 154.94 133.35 0)
		(effects
			(font
				(size 1.27 1.27)
			)
			(justify left bottom)
		)
	)
	(text "NOTE:\noptional \nexternal divider "
		(exclude_from_sim no)
		(at 321.945 76.2 0)
		(effects
			(font
				(size 1.27 1.27)
			)
			(justify left bottom)
		)
	)
	(text "X"
		(exclude_from_sim no)
		(at 167.64 138.43 0)
		(effects
			(font
				(size 1.27 1.27)
			)
			(justify left bottom)
		)
	)
	(text "I2C: 0x10"
		(exclude_from_sim no)
		(at 156.21 241.3 0)
		(effects
			(font
				(size 1.27 1.27)
			)
			(justify left bottom)
		)
	)
	(text "I2C: 0x69"
		(exclude_from_sim no)
		(at 158.75 110.49 0)
		(effects
			(font
				(size 1.27 1.27)
			)
			(justify left bottom)
		)
	)
	(text "NOTE:\noptional \nexternal divider "
		(exclude_from_sim no)
		(at 290.83 76.2 0)
		(effects
			(font
				(size 1.27 1.27)
			)
			(justify left bottom)
		)
	)
	(text "NOTE:\noptional \nexternal divider "
		(exclude_from_sim no)
		(at 291.465 112.395 0)
		(effects
			(font
				(size 1.27 1.27)
			)
			(justify left bottom)
		)
	)
	(text "1"
		(exclude_from_sim no)
		(at 167.64 128.27 0)
		(effects
			(font
				(size 1.27 1.27)
			)
			(justify left bottom)
		)
	)
	(text "Soft start delay time slot"
		(exclude_from_sim no)
		(at 151.13 124.46 0)
		(effects
			(font
				(size 1.27 1.27)
			)
			(justify left bottom)
		)
	)
	(text "X"
		(exclude_from_sim no)
		(at 171.45 135.89 0)
		(effects
			(font
				(size 1.27 1.27)
			)
			(justify left bottom)
		)
	)
	(junction
		(at 308.61 68.58)
		(diameter 0)
		(color 0 0 0 0)
	)
	(junction
		(at 194.31 62.23)
		(diameter 0)
		(color 0 0 0 0)
	)
	(junction
		(at 203.2 52.07)
		(diameter 0)
		(color 0 0 0 0)
	)
	(junction
		(at 203.2 101.6)
		(diameter 0)
		(color 0 0 0 0)
	)
	(junction
		(at 229.87 52.07)
		(diameter 0)
		(color 0 0 0 0)
	)
	(junction
		(at 242.57 110.49)
		(diameter 0)
		(color 0 0 0 0)
	)
	(junction
		(at 339.09 68.58)
		(diameter 0)
		(color 0 0 0 0)
	)
	(junction
		(at 222.25 73.66)
		(diameter 0)
		(color 0 0 0 0)
	)
	(junction
		(at 203.2 91.44)
		(diameter 0)
		(color 0 0 0 0)
	)
	(junction
		(at 203.2 73.66)
		(diameter 0)
		(color 0 0 0 0)
	)
	(junction
		(at 241.3 52.07)
		(diameter 0)
		(color 0 0 0 0)
	)
	(junction
		(at 251.46 73.66)
		(diameter 0)
		(color 0 0 0 0)
	)
	(junction
		(at 222.25 52.07)
		(diameter 0)
		(color 0 0 0 0)
	)
	(junction
		(at 229.87 73.66)
		(diameter 0)
		(color 0 0 0 0)
	)
	(junction
		(at 241.3 73.66)
		(diameter 0)
		(color 0 0 0 0)
	)
	(junction
		(at 250.19 91.44)
		(diameter 0)
		(color 0 0 0 0)
	)
	(junction
		(at 229.87 110.49)
		(diameter 0)
		(color 0 0 0 0)
	)
	(junction
		(at 241.3 91.44)
		(diameter 0)
		(color 0 0 0 0)
	)
	(junction
		(at 250.19 110.49)
		(diameter 0)
		(color 0 0 0 0)
	)
	(junction
		(at 128.27 210.82)
		(diameter 0)
		(color 0 0 0 0)
	)
	(junction
		(at 309.88 104.14)
		(diameter 0)
		(color 0 0 0 0)
	)
	(junction
		(at 222.25 110.49)
		(diameter 0)
		(color 0 0 0 0)
	)
	(junction
		(at 203.2 62.23)
		(diameter 0)
		(color 0 0 0 0)
	)
	(junction
		(at 147.32 231.14)
		(diameter 0)
		(color 0 0 0 0)
	)
	(junction
		(at 229.87 91.44)
		(diameter 0)
		(color 0 0 0 0)
	)
	(junction
		(at 203.2 110.49)
		(diameter 0)
		(color 0 0 0 0)
	)
	(junction
		(at 138.43 50.8)
		(diameter 0)
		(color 0 0 0 0)
	)
	(junction
		(at 128.27 50.8)
		(diameter 0)
		(color 0 0 0 0)
	)
	(junction
		(at 250.19 52.07)
		(diameter 0)
		(color 0 0 0 0)
	)
	(junction
		(at 194.31 73.66)
		(diameter 0)
		(color 0 0 0 0)
	)
	(junction
		(at 147.32 233.68)
		(diameter 0)
		(color 0 0 0 0)
	)
	(junction
		(at 222.25 91.44)
		(diameter 0)
		(color 0 0 0 0)
	)
	(junction
		(at 128.27 59.69)
		(diameter 0)
		(color 0 0 0 0)
	)
	(junction
		(at 203.2 83.82)
		(diameter 0)
		(color 0 0 0 0)
	)
	(junction
		(at 339.09 104.14)
		(diameter 0)
		(color 0 0 0 0)
	)
	(junction
		(at 194.31 52.07)
		(diameter 0)
		(color 0 0 0 0)
	)
	(no_connect
		(at 177.8 83.82)
	)
	(no_connect
		(at 148.59 222.25)
	)
	(no_connect
		(at 177.8 71.12)
	)
	(no_connect
		(at 148.59 219.71)
	)
	(wire
		(pts
			(xy 241.3 90.17) (xy 241.3 91.44)
		)
		(stroke
			(width 0)
			(type default)
		)
	)
	(polyline
		(pts
			(xy 154.94 138.43) (xy 177.8 138.43)
		)
		(stroke
			(width 0)
			(type default)
		)
	)
	(wire
		(pts
			(xy 128.27 213.36) (xy 128.27 210.82)
		)
		(stroke
			(width 0)
			(type default)
		)
	)
	(wire
		(pts
			(xy 128.27 224.79) (xy 128.27 218.44)
		)
		(stroke
			(width 0)
			(type default)
		)
	)
	(wire
		(pts
			(xy 194.31 52.07) (xy 203.2 52.07)
		)
		(stroke
			(width 0)
			(type default)
		)
	)
	(polyline
		(pts
			(xy 154.94 138.43) (xy 154.94 138.43)
		)
		(stroke
			(width 0)
			(type default)
		)
	)
	(wire
		(pts
			(xy 177.8 76.2) (xy 189.23 76.2)
		)
		(stroke
			(width 0)
			(type default)
		)
	)
	(wire
		(pts
			(xy 222.25 99.06) (xy 210.82 99.06)
		)
		(stroke
			(width 0)
			(type default)
		)
	)
	(wire
		(pts
			(xy 173.99 226.06) (xy 198.12 226.06)
		)
		(stroke
			(width 0)
			(type default)
		)
	)
	(wire
		(pts
			(xy 222.25 59.69) (xy 210.82 59.69)
		)
		(stroke
			(width 0)
			(type default)
		)
	)
	(wire
		(pts
			(xy 308.61 76.2) (xy 308.61 80.01)
		)
		(stroke
			(width 0)
			(type default)
		)
	)
	(wire
		(pts
			(xy 203.2 110.49) (xy 222.25 110.49)
		)
		(stroke
			(width 0)
			(type default)
		)
	)
	(wire
		(pts
			(xy 138.43 58.42) (xy 138.43 59.69)
		)
		(stroke
			(width 0)
			(type default)
		)
	)
	(wire
		(pts
			(xy 148.59 68.58) (xy 149.86 68.58)
		)
		(stroke
			(width 0)
			(type default)
		)
	)
	(wire
		(pts
			(xy 241.3 91.44) (xy 250.19 91.44)
		)
		(stroke
			(width 0)
			(type default)
		)
	)
	(wire
		(pts
			(xy 229.87 59.69) (xy 248.92 59.69)
		)
		(stroke
			(width 0)
			(type default)
		)
	)
	(polyline
		(pts
			(xy 320.04 105.41) (xy 320.04 114.3)
		)
		(stroke
			(width 0)
			(type default)
		)
	)
	(wire
		(pts
			(xy 203.2 101.6) (xy 203.2 102.87)
		)
		(stroke
			(width 0)
			(type default)
		)
	)
	(wire
		(pts
			(xy 229.87 59.69) (xy 229.87 58.42)
		)
		(stroke
			(width 0)
			(type default)
		)
	)
	(polyline
		(pts
			(xy 162.56 127) (xy 162.56 138.43)
		)
		(stroke
			(width 0)
			(type default)
		)
	)
	(wire
		(pts
			(xy 144.78 99.06) (xy 149.86 99.06)
		)
		(stroke
			(width 0)
			(type default)
		)
	)
	(wire
		(pts
			(xy 229.87 116.84) (xy 229.87 118.11)
		)
		(stroke
			(width 0)
			(type default)
		)
	)
	(polyline
		(pts
			(xy 177.8 121.92) (xy 177.8 138.43)
		)
		(stroke
			(width 0)
			(type default)
		)
	)
	(wire
		(pts
			(xy 303.53 68.58) (xy 308.61 68.58)
		)
		(stroke
			(width 0)
			(type default)
		)
	)
	(polyline
		(pts
			(xy 349.25 105.41) (xy 349.25 114.3)
		)
		(stroke
			(width 0)
			(type default)
		)
	)
	(wire
		(pts
			(xy 180.34 217.17) (xy 198.12 217.17)
		)
		(stroke
			(width 0)
			(type default)
		)
	)
	(wire
		(pts
			(xy 203.2 62.23) (xy 203.2 63.5)
		)
		(stroke
			(width 0)
			(type default)
		)
	)
	(polyline
		(pts
			(xy 149.86 135.89) (xy 177.8 135.89)
		)
		(stroke
			(width 0)
			(type default)
		)
	)
	(wire
		(pts
			(xy 185.42 52.07) (xy 194.31 52.07)
		)
		(stroke
			(width 0)
			(type default)
		)
	)
	(wire
		(pts
			(xy 186.69 73.66) (xy 177.8 73.66)
		)
		(stroke
			(width 0)
			(type default)
		)
	)
	(wire
		(pts
			(xy 250.19 91.44) (xy 251.46 91.44)
		)
		(stroke
			(width 0)
			(type default)
		)
	)
	(wire
		(pts
			(xy 331.47 57.15) (xy 339.09 57.15)
		)
		(stroke
			(width 0)
			(type default)
		)
	)
	(wire
		(pts
			(xy 303.53 104.14) (xy 309.88 104.14)
		)
		(stroke
			(width 0)
			(type default)
		)
	)
	(wire
		(pts
			(xy 199.39 101.6) (xy 203.2 101.6)
		)
		(stroke
			(width 0)
			(type default)
		)
	)
	(wire
		(pts
			(xy 228.6 110.49) (xy 229.87 110.49)
		)
		(stroke
			(width 0)
			(type default)
		)
	)
	(polyline
		(pts
			(xy 177.8 125.73) (xy 162.56 125.73)
		)
		(stroke
			(width 0)
			(type default)
		)
	)
	(polyline
		(pts
			(xy 151.13 138.43) (xy 154.94 138.43)
		)
		(stroke
			(width 0)
			(type default)
		)
	)
	(wire
		(pts
			(xy 203.2 91.44) (xy 222.25 91.44)
		)
		(stroke
			(width 0)
			(type default)
		)
	)
	(wire
		(pts
			(xy 222.25 81.28) (xy 212.09 81.28)
		)
		(stroke
			(width 0)
			(type default)
		)
	)
	(wire
		(pts
			(xy 229.87 81.28) (xy 247.65 81.28)
		)
		(stroke
			(width 0)
			(type default)
		)
	)
	(wire
		(pts
			(xy 194.31 73.66) (xy 203.2 73.66)
		)
		(stroke
			(width 0)
			(type default)
		)
	)
	(polyline
		(pts
			(xy 166.37 125.73) (xy 166.37 125.73)
		)
		(stroke
			(width 0)
			(type default)
		)
	)
	(wire
		(pts
			(xy 177.8 91.44) (xy 203.2 91.44)
		)
		(stroke
			(width 0)
			(type default)
		)
	)
	(wire
		(pts
			(xy 146.05 78.74) (xy 149.86 78.74)
		)
		(stroke
			(width 0)
			(type default)
		)
	)
	(wire
		(pts
			(xy 180.34 210.82) (xy 198.12 210.82)
		)
		(stroke
			(width 0)
			(type default)
		)
	)
	(wire
		(pts
			(xy 128.27 58.42) (xy 128.27 59.69)
		)
		(stroke
			(width 0)
			(type default)
		)
	)
	(wire
		(pts
			(xy 194.31 59.69) (xy 194.31 62.23)
		)
		(stroke
			(width 0)
			(type default)
		)
	)
	(wire
		(pts
			(xy 173.99 217.17) (xy 175.26 217.17)
		)
		(stroke
			(width 0)
			(type default)
		)
	)
	(wire
		(pts
			(xy 242.57 110.49) (xy 250.19 110.49)
		)
		(stroke
			(width 0)
			(type default)
		)
	)
	(wire
		(pts
			(xy 242.57 109.22) (xy 242.57 110.49)
		)
		(stroke
			(width 0)
			(type default)
		)
	)
	(wire
		(pts
			(xy 241.3 73.66) (xy 251.46 73.66)
		)
		(stroke
			(width 0)
			(type default)
		)
	)
	(wire
		(pts
			(xy 229.87 91.44) (xy 241.3 91.44)
		)
		(stroke
			(width 0)
			(type default)
		)
	)
	(wire
		(pts
			(xy 339.09 101.6) (xy 339.09 104.14)
		)
		(stroke
			(width 0)
			(type default)
		)
	)
	(polyline
		(pts
			(xy 290.83 69.85) (xy 318.77 69.85)
		)
		(stroke
			(width 0)
			(type default)
		)
	)
	(wire
		(pts
			(xy 194.31 83.82) (xy 203.2 83.82)
		)
		(stroke
			(width 0)
			(type default)
		)
	)
	(wire
		(pts
			(xy 228.6 52.07) (xy 229.87 52.07)
		)
		(stroke
			(width 0)
			(type default)
		)
	)
	(polyline
		(pts
			(xy 349.25 77.47) (xy 321.31 77.47)
		)
		(stroke
			(width 0)
			(type default)
		)
	)
	(wire
		(pts
			(xy 147.32 217.17) (xy 148.59 217.17)
		)
		(stroke
			(width 0)
			(type default)
		)
	)
	(wire
		(pts
			(xy 148.59 231.14) (xy 147.32 231.14)
		)
		(stroke
			(width 0)
			(type default)
		)
	)
	(wire
		(pts
			(xy 194.31 73.66) (xy 194.31 76.2)
		)
		(stroke
			(width 0)
			(type default)
		)
	)
	(wire
		(pts
			(xy 229.87 99.06) (xy 229.87 97.79)
		)
		(stroke
			(width 0)
			(type default)
		)
	)
	(wire
		(pts
			(xy 229.87 81.28) (xy 229.87 80.01)
		)
		(stroke
			(width 0)
			(type default)
		)
	)
	(polyline
		(pts
			(xy 149.86 138.43) (xy 151.13 138.43)
		)
		(stroke
			(width 0)
			(type default)
		)
	)
	(wire
		(pts
			(xy 250.19 52.07) (xy 250.19 49.53)
		)
		(stroke
			(width 0)
			(type default)
		)
	)
	(wire
		(pts
			(xy 128.27 210.82) (xy 148.59 210.82)
		)
		(stroke
			(width 0)
			(type default)
		)
	)
	(polyline
		(pts
			(xy 177.8 121.92) (xy 149.86 121.92)
		)
		(stroke
			(width 0)
			(type default)
		)
	)
	(wire
		(pts
			(xy 148.59 104.14) (xy 148.59 105.41)
		)
		(stroke
			(width 0)
			(type default)
		)
	)
	(wire
		(pts
			(xy 148.59 87.63) (xy 149.86 87.63)
		)
		(stroke
			(width 0)
			(type default)
		)
	)
	(wire
		(pts
			(xy 177.8 81.28) (xy 191.77 81.28)
		)
		(stroke
			(width 0)
			(type default)
		)
	)
	(wire
		(pts
			(xy 203.2 81.28) (xy 203.2 83.82)
		)
		(stroke
			(width 0)
			(type default)
		)
	)
	(wire
		(pts
			(xy 229.87 110.49) (xy 242.57 110.49)
		)
		(stroke
			(width 0)
			(type default)
		)
	)
	(polyline
		(pts
			(xy 320.04 114.3) (xy 290.83 114.3)
		)
		(stroke
			(width 0)
			(type default)
		)
	)
	(wire
		(pts
			(xy 339.09 93.98) (xy 339.09 96.52)
		)
		(stroke
			(width 0)
			(type default)
		)
	)
	(wire
		(pts
			(xy 339.09 111.76) (xy 339.09 114.3)
		)
		(stroke
			(width 0)
			(type default)
		)
	)
	(polyline
		(pts
			(xy 149.86 130.81) (xy 177.8 130.81)
		)
		(stroke
			(width 0)
			(type default)
		)
	)
	(polyline
		(pts
			(xy 290.83 105.41) (xy 320.04 105.41)
		)
		(stroke
			(width 0)
			(type default)
		)
	)
	(polyline
		(pts
			(xy 162.56 125.73) (xy 162.56 127)
		)
		(stroke
			(width 0)
			(type default)
		)
	)
	(wire
		(pts
			(xy 173.99 213.36) (xy 198.12 213.36)
		)
		(stroke
			(width 0)
			(type default)
		)
	)
	(wire
		(pts
			(xy 339.09 104.14) (xy 339.09 106.68)
		)
		(stroke
			(width 0)
			(type default)
		)
	)
	(polyline
		(pts
			(xy 290.83 69.85) (xy 290.83 77.47)
		)
		(stroke
			(width 0)
			(type default)
		)
	)
	(wire
		(pts
			(xy 199.39 96.52) (xy 199.39 101.6)
		)
		(stroke
			(width 0)
			(type default)
		)
	)
	(wire
		(pts
			(xy 138.43 59.69) (xy 128.27 59.69)
		)
		(stroke
			(width 0)
			(type default)
		)
	)
	(wire
		(pts
			(xy 222.25 58.42) (xy 222.25 59.69)
		)
		(stroke
			(width 0)
			(type default)
		)
	)
	(polyline
		(pts
			(xy 349.25 114.3) (xy 321.31 114.3)
		)
		(stroke
			(width 0)
			(type default)
		)
	)
	(wire
		(pts
			(xy 189.23 76.2) (xy 189.23 62.23)
		)
		(stroke
			(width 0)
			(type default)
		)
	)
	(wire
		(pts
			(xy 308.61 57.15) (xy 308.61 60.96)
		)
		(stroke
			(width 0)
			(type default)
		)
	)
	(polyline
		(pts
			(xy 12.7 163.83) (xy 407.67 163.83)
		)
		(stroke
			(width 0)
			(type default)
		)
	)
	(wire
		(pts
			(xy 339.09 66.04) (xy 339.09 68.58)
		)
		(stroke
			(width 0)
			(type default)
		)
	)
	(wire
		(pts
			(xy 339.09 68.58) (xy 339.09 71.12)
		)
		(stroke
			(width 0)
			(type default)
		)
	)
	(wire
		(pts
			(xy 203.2 116.84) (xy 203.2 118.11)
		)
		(stroke
			(width 0)
			(type default)
		)
	)
	(wire
		(pts
			(xy 203.2 99.06) (xy 203.2 101.6)
		)
		(stroke
			(width 0)
			(type default)
		)
	)
	(wire
		(pts
			(xy 339.09 76.2) (xy 339.09 78.74)
		)
		(stroke
			(width 0)
			(type default)
		)
	)
	(wire
		(pts
			(xy 138.43 50.8) (xy 148.59 50.8)
		)
		(stroke
			(width 0)
			(type default)
		)
	)
	(wire
		(pts
			(xy 222.25 73.66) (xy 223.52 73.66)
		)
		(stroke
			(width 0)
			(type default)
		)
	)
	(polyline
		(pts
			(xy 149.86 128.27) (xy 177.8 128.27)
		)
		(stroke
			(width 0)
			(type default)
		)
	)
	(wire
		(pts
			(xy 309.88 111.76) (xy 309.88 115.57)
		)
		(stroke
			(width 0)
			(type default)
		)
	)
	(wire
		(pts
			(xy 334.01 68.58) (xy 339.09 68.58)
		)
		(stroke
			(width 0)
			(type default)
		)
	)
	(wire
		(pts
			(xy 251.46 72.39) (xy 251.46 73.66)
		)
		(stroke
			(width 0)
			(type default)
		)
	)
	(wire
		(pts
			(xy 147.32 231.14) (xy 147.32 233.68)
		)
		(stroke
			(width 0)
			(type default)
		)
	)
	(wire
		(pts
			(xy 128.27 71.12) (xy 128.27 73.66)
		)
		(stroke
			(width 0)
			(type default)
		)
	)
	(wire
		(pts
			(xy 189.23 62.23) (xy 194.31 62.23)
		)
		(stroke
			(width 0)
			(type default)
		)
	)
	(wire
		(pts
			(xy 173.99 232.41) (xy 198.12 232.41)
		)
		(stroke
			(width 0)
			(type default)
		)
	)
	(wire
		(pts
			(xy 250.19 90.17) (xy 250.19 91.44)
		)
		(stroke
			(width 0)
			(type default)
		)
	)
	(wire
		(pts
			(xy 298.45 93.98) (xy 309.88 93.98)
		)
		(stroke
			(width 0)
			(type default)
		)
	)
	(wire
		(pts
			(xy 173.99 210.82) (xy 175.26 210.82)
		)
		(stroke
			(width 0)
			(type default)
		)
	)
	(wire
		(pts
			(xy 128.27 207.01) (xy 128.27 210.82)
		)
		(stroke
			(width 0)
			(type default)
		)
	)
	(wire
		(pts
			(xy 203.2 83.82) (xy 203.2 85.09)
		)
		(stroke
			(width 0)
			(type default)
		)
	)
	(wire
		(pts
			(xy 222.25 91.44) (xy 223.52 91.44)
		)
		(stroke
			(width 0)
			(type default)
		)
	)
	(wire
		(pts
			(xy 148.59 104.14) (xy 149.86 104.14)
		)
		(stroke
			(width 0)
			(type default)
		)
	)
	(polyline
		(pts
			(xy 321.31 69.85) (xy 349.25 69.85)
		)
		(stroke
			(width 0)
			(type default)
		)
	)
	(wire
		(pts
			(xy 196.85 110.49) (xy 203.2 110.49)
		)
		(stroke
			(width 0)
			(type default)
		)
	)
	(wire
		(pts
			(xy 128.27 59.69) (xy 128.27 60.96)
		)
		(stroke
			(width 0)
			(type default)
		)
	)
	(wire
		(pts
			(xy 191.77 81.28) (xy 191.77 73.66)
		)
		(stroke
			(width 0)
			(type default)
		)
	)
	(polyline
		(pts
			(xy 173.99 125.73) (xy 173.99 138.43)
		)
		(stroke
			(width 0)
			(type default)
		)
	)
	(wire
		(pts
			(xy 328.93 93.98) (xy 339.09 93.98)
		)
		(stroke
			(width 0)
			(type default)
		)
	)
	(polyline
		(pts
			(xy 149.86 133.35) (xy 149.86 138.43)
		)
		(stroke
			(width 0)
			(type default)
		)
	)
	(wire
		(pts
			(xy 194.31 52.07) (xy 194.31 54.61)
		)
		(stroke
			(width 0)
			(type default)
		)
	)
	(wire
		(pts
			(xy 148.59 90.17) (xy 149.86 90.17)
		)
		(stroke
			(width 0)
			(type default)
		)
	)
	(wire
		(pts
			(xy 173.99 229.87) (xy 175.26 229.87)
		)
		(stroke
			(width 0)
			(type default)
		)
	)
	(wire
		(pts
			(xy 203.2 52.07) (xy 203.2 54.61)
		)
		(stroke
			(width 0)
			(type default)
		)
	)
	(wire
		(pts
			(xy 222.25 97.79) (xy 222.25 99.06)
		)
		(stroke
			(width 0)
			(type default)
		)
	)
	(wire
		(pts
			(xy 298.45 57.15) (xy 308.61 57.15)
		)
		(stroke
			(width 0)
			(type default)
		)
	)
	(wire
		(pts
			(xy 241.3 72.39) (xy 241.3 73.66)
		)
		(stroke
			(width 0)
			(type default)
		)
	)
	(wire
		(pts
			(xy 229.87 73.66) (xy 241.3 73.66)
		)
		(stroke
			(width 0)
			(type default)
		)
	)
	(wire
		(pts
			(xy 191.77 73.66) (xy 194.31 73.66)
		)
		(stroke
			(width 0)
			(type default)
		)
	)
	(wire
		(pts
			(xy 173.99 223.52) (xy 175.26 223.52)
		)
		(stroke
			(width 0)
			(type default)
		)
	)
	(wire
		(pts
			(xy 194.31 81.28) (xy 194.31 83.82)
		)
		(stroke
			(width 0)
			(type default)
		)
	)
	(wire
		(pts
			(xy 228.6 73.66) (xy 229.87 73.66)
		)
		(stroke
			(width 0)
			(type default)
		)
	)
	(wire
		(pts
			(xy 241.3 52.07) (xy 250.19 52.07)
		)
		(stroke
			(width 0)
			(type default)
		)
	)
	(wire
		(pts
			(xy 185.42 52.07) (xy 185.42 68.58)
		)
		(stroke
			(width 0)
			(type default)
		)
	)
	(wire
		(pts
			(xy 147.32 214.63) (xy 148.59 214.63)
		)
		(stroke
			(width 0)
			(type default)
		)
	)
	(wire
		(pts
			(xy 229.87 118.11) (xy 250.19 118.11)
		)
		(stroke
			(width 0)
			(type default)
		)
	)
	(polyline
		(pts
			(xy 149.86 133.35) (xy 177.8 133.35)
		)
		(stroke
			(width 0)
			(type default)
		)
	)
	(wire
		(pts
			(xy 308.61 66.04) (xy 308.61 68.58)
		)
		(stroke
			(width 0)
			(type default)
		)
	)
	(wire
		(pts
			(xy 128.27 50.8) (xy 128.27 53.34)
		)
		(stroke
			(width 0)
			(type default)
		)
	)
	(wire
		(pts
			(xy 203.2 110.49) (xy 203.2 111.76)
		)
		(stroke
			(width 0)
			(type default)
		)
	)
	(wire
		(pts
			(xy 309.88 93.98) (xy 309.88 96.52)
		)
		(stroke
			(width 0)
			(type default)
		)
	)
	(wire
		(pts
			(xy 138.43 50.8) (xy 138.43 53.34)
		)
		(stroke
			(width 0)
			(type default)
		)
	)
	(wire
		(pts
			(xy 308.61 68.58) (xy 308.61 71.12)
		)
		(stroke
			(width 0)
			(type default)
		)
	)
	(polyline
		(pts
			(xy 149.86 121.92) (xy 149.86 133.35)
		)
		(stroke
			(width 0)
			(type default)
		)
	)
	(wire
		(pts
			(xy 173.99 219.71) (xy 198.12 219.71)
		)
		(stroke
			(width 0)
			(type default)
		)
	)
	(wire
		(pts
			(xy 241.3 50.8) (xy 241.3 52.07)
		)
		(stroke
			(width 0)
			(type default)
		)
	)
	(wire
		(pts
			(xy 222.25 80.01) (xy 222.25 81.28)
		)
		(stroke
			(width 0)
			(type default)
		)
	)
	(wire
		(pts
			(xy 128.27 71.12) (xy 149.86 71.12)
		)
		(stroke
			(width 0)
			(type default)
		)
	)
	(wire
		(pts
			(xy 250.19 109.22) (xy 250.19 110.49)
		)
		(stroke
			(width 0)
			(type default)
		)
	)
	(wire
		(pts
			(xy 177.8 101.6) (xy 196.85 101.6)
		)
		(stroke
			(width 0)
			(type default)
		)
	)
	(wire
		(pts
			(xy 222.25 52.07) (xy 223.52 52.07)
		)
		(stroke
			(width 0)
			(type default)
		)
	)
	(wire
		(pts
			(xy 180.34 223.52) (xy 198.12 223.52)
		)
		(stroke
			(width 0)
			(type default)
		)
	)
	(wire
		(pts
			(xy 309.88 104.14) (xy 309.88 106.68)
		)
		(stroke
			(width 0)
			(type default)
		)
	)
	(wire
		(pts
			(xy 177.8 96.52) (xy 199.39 96.52)
		)
		(stroke
			(width 0)
			(type default)
		)
	)
	(wire
		(pts
			(xy 147.32 233.68) (xy 147.32 236.22)
		)
		(stroke
			(width 0)
			(type default)
		)
	)
	(polyline
		(pts
			(xy 321.31 69.85) (xy 321.31 77.47)
		)
		(stroke
			(width 0)
			(type default)
		)
	)
	(wire
		(pts
			(xy 334.01 104.14) (xy 339.09 104.14)
		)
		(stroke
			(width 0)
			(type default)
		)
	)
	(wire
		(pts
			(xy 339.09 57.15) (xy 339.09 60.96)
		)
		(stroke
			(width 0)
			(type default)
		)
	)
	(wire
		(pts
			(xy 196.85 101.6) (xy 196.85 110.49)
		)
		(stroke
			(width 0)
			(type default)
		)
	)
	(polyline
		(pts
			(xy 321.31 105.41) (xy 349.25 105.41)
		)
		(stroke
			(width 0)
			(type default)
		)
	)
	(wire
		(pts
			(xy 177.8 68.58) (xy 185.42 68.58)
		)
		(stroke
			(width 0)
			(type default)
		)
	)
	(wire
		(pts
			(xy 251.46 73.66) (xy 252.73 73.66)
		)
		(stroke
			(width 0)
			(type default)
		)
	)
	(polyline
		(pts
			(xy 290.83 105.41) (xy 290.83 114.3)
		)
		(stroke
			(width 0)
			(type default)
		)
	)
	(wire
		(pts
			(xy 222.25 118.11) (xy 210.82 118.11)
		)
		(stroke
			(width 0)
			(type default)
		)
	)
	(wire
		(pts
			(xy 203.2 91.44) (xy 203.2 93.98)
		)
		(stroke
			(width 0)
			(type default)
		)
	)
	(wire
		(pts
			(xy 203.2 73.66) (xy 203.2 76.2)
		)
		(stroke
			(width 0)
			(type default)
		)
	)
	(wire
		(pts
			(xy 203.2 52.07) (xy 222.25 52.07)
		)
		(stroke
			(width 0)
			(type default)
		)
	)
	(wire
		(pts
			(xy 148.59 50.8) (xy 148.59 68.58)
		)
		(stroke
			(width 0)
			(type default)
		)
	)
	(wire
		(pts
			(xy 250.19 52.07) (xy 252.73 52.07)
		)
		(stroke
			(width 0)
			(type default)
		)
	)
	(wire
		(pts
			(xy 128.27 49.53) (xy 128.27 50.8)
		)
		(stroke
			(width 0)
			(type default)
		)
	)
	(wire
		(pts
			(xy 186.69 104.14) (xy 177.8 104.14)
		)
		(stroke
			(width 0)
			(type default)
		)
	)
	(polyline
		(pts
			(xy 318.77 69.85) (xy 318.77 77.47)
		)
		(stroke
			(width 0)
			(type default)
		)
	)
	(polyline
		(pts
			(xy 321.31 105.41) (xy 321.31 114.3)
		)
		(stroke
			(width 0)
			(type default)
		)
	)
	(polyline
		(pts
			(xy 170.18 125.73) (xy 170.18 138.43)
		)
		(stroke
			(width 0)
			(type default)
		)
	)
	(wire
		(pts
			(xy 309.88 101.6) (xy 309.88 104.14)
		)
		(stroke
			(width 0)
			(type default)
		)
	)
	(wire
		(pts
			(xy 148.59 233.68) (xy 147.32 233.68)
		)
		(stroke
			(width 0)
			(type default)
		)
	)
	(wire
		(pts
			(xy 186.69 86.36) (xy 177.8 86.36)
		)
		(stroke
			(width 0)
			(type default)
		)
	)
	(wire
		(pts
			(xy 229.87 52.07) (xy 241.3 52.07)
		)
		(stroke
			(width 0)
			(type default)
		)
	)
	(wire
		(pts
			(xy 186.69 93.98) (xy 177.8 93.98)
		)
		(stroke
			(width 0)
			(type default)
		)
	)
	(polyline
		(pts
			(xy 166.37 125.73) (xy 166.37 138.43)
		)
		(stroke
			(width 0)
			(type default)
		)
	)
	(wire
		(pts
			(xy 128.27 78.74) (xy 128.27 81.28)
		)
		(stroke
			(width 0)
			(type default)
		)
	)
	(wire
		(pts
			(xy 228.6 91.44) (xy 229.87 91.44)
		)
		(stroke
			(width 0)
			(type default)
		)
	)
	(wire
		(pts
			(xy 148.59 227.33) (xy 147.32 227.33)
		)
		(stroke
			(width 0)
			(type default)
		)
	)
	(polyline
		(pts
			(xy 349.25 69.85) (xy 349.25 77.47)
		)
		(stroke
			(width 0)
			(type default)
		)
	)
	(wire
		(pts
			(xy 128.27 50.8) (xy 138.43 50.8)
		)
		(stroke
			(width 0)
			(type default)
		)
	)
	(wire
		(pts
			(xy 147.32 227.33) (xy 147.32 231.14)
		)
		(stroke
			(width 0)
			(type default)
		)
	)
	(wire
		(pts
			(xy 180.34 229.87) (xy 198.12 229.87)
		)
		(stroke
			(width 0)
			(type default)
		)
	)
	(polyline
		(pts
			(xy 318.77 77.47) (xy 290.83 77.47)
		)
		(stroke
			(width 0)
			(type default)
		)
	)
	(wire
		(pts
			(xy 229.87 99.06) (xy 248.92 99.06)
		)
		(stroke
			(width 0)
			(type default)
		)
	)
	(wire
		(pts
			(xy 222.25 110.49) (xy 223.52 110.49)
		)
		(stroke
			(width 0)
			(type default)
		)
	)
	(wire
		(pts
			(xy 203.2 73.66) (xy 222.25 73.66)
		)
		(stroke
			(width 0)
			(type default)
		)
	)
	(wire
		(pts
			(xy 203.2 59.69) (xy 203.2 62.23)
		)
		(stroke
			(width 0)
			(type default)
		)
	)
	(wire
		(pts
			(xy 128.27 224.79) (xy 148.59 224.79)
		)
		(stroke
			(width 0)
			(type default)
		)
	)
	(wire
		(pts
			(xy 250.19 110.49) (xy 251.46 110.49)
		)
		(stroke
			(width 0)
			(type default)
		)
	)
	(wire
		(pts
			(xy 194.31 62.23) (xy 203.2 62.23)
		)
		(stroke
			(width 0)
			(type default)
		)
	)
	(wire
		(pts
			(xy 104.14 212.09) (xy 104.14 213.36)
		)
		(stroke
			(width 0)
			(type default)
		)
	)
	(wire
		(pts
			(xy 222.25 116.84) (xy 222.25 118.11)
		)
		(stroke
			(width 0)
			(type default)
		)
	)
	(label "VDDQ_SEN_+"
		(at 210.82 99.06 0)
		(effects
			(font
				(size 1.27 1.27)
			)
			(justify left bottom)
		)
	)
	(label "VDDQ_SEN_-"
		(at 248.92 99.06 180)
		(effects
			(font
				(size 1.27 1.27)
			)
			(justify right bottom)
		)
	)
	(label "1V2_local"
		(at 328.93 93.98 0)
		(effects
			(font
				(size 1.27 1.27)
			)
			(justify left bottom)
		)
	)
	(label "3V3_local"
		(at 298.45 57.15 0)
		(effects
			(font
				(size 1.27 1.27)
			)
			(justify left bottom)
		)
	)
	(label "5V_SEN_-"
		(at 247.65 81.28 180)
		(effects
			(font
				(size 1.27 1.27)
			)
			(justify right bottom)
		)
	)
	(label "5V_SEN_+"
		(at 212.09 81.28 0)
		(effects
			(font
				(size 1.27 1.27)
			)
			(justify left bottom)
		)
	)
	(label "1V2_SEN_+"
		(at 198.12 229.87 180)
		(effects
			(font
				(size 1.27 1.27)
			)
			(justify right bottom)
		)
	)
	(label "1V2_SEN_-"
		(at 250.19 118.11 180)
		(effects
			(font
				(size 1.27 1.27)
			)
			(justify right bottom)
		)
	)
	(label "3V3_SEN_-"
		(at 198.12 213.36 180)
		(effects
			(font
				(size 1.27 1.27)
			)
			(justify right bottom)
		)
	)
	(label "1V2_SEN_-"
		(at 198.12 232.41 180)
		(effects
			(font
				(size 1.27 1.27)
			)
			(justify right bottom)
		)
	)
	(label "5V_SEN_-"
		(at 198.12 219.71 180)
		(effects
			(font
				(size 1.27 1.27)
			)
			(justify right bottom)
		)
	)
	(label "3V3_SEN_-"
		(at 248.92 59.69 180)
		(effects
			(font
				(size 1.27 1.27)
			)
			(justify right bottom)
		)
	)
	(label "5V_SEN_+"
		(at 198.12 217.17 180)
		(effects
			(font
				(size 1.27 1.27)
			)
			(justify right bottom)
		)
	)
	(label "FB6"
		(at 186.69 86.36 180)
		(effects
			(font
				(size 1.27 1.27)
			)
			(justify right bottom)
		)
	)
	(label "QDCDC2_VCC"
		(at 128.27 71.12 0)
		(effects
			(font
				(size 1.27 1.27)
			)
			(justify left bottom)
		)
	)
	(label "VDDQ_SEN_-"
		(at 198.12 226.06 180)
		(effects
			(font
				(size 1.27 1.27)
			)
			(justify right bottom)
		)
	)
	(label "VDDQ_SEN_+"
		(at 198.12 223.52 180)
		(effects
			(font
				(size 1.27 1.27)
			)
			(justify right bottom)
		)
	)
	(label "FB5"
		(at 303.53 68.58 0)
		(effects
			(font
				(size 1.27 1.27)
			)
			(justify left bottom)
		)
	)
	(label "VDDQ_local"
		(at 331.47 57.15 0)
		(effects
			(font
				(size 1.27 1.27)
			)
			(justify left bottom)
		)
	)
	(label "5V_local"
		(at 298.45 93.98 0)
		(effects
			(font
				(size 1.27 1.27)
			)
			(justify left bottom)
		)
	)
	(label "FB7"
		(at 334.01 68.58 0)
		(effects
			(font
				(size 1.27 1.27)
			)
			(justify left bottom)
		)
	)
	(label "3V3_local"
		(at 203.2 52.07 0)
		(effects
			(font
				(size 1.27 1.27)
			)
			(justify left bottom)
		)
	)
	(label "FB8"
		(at 186.69 104.14 180)
		(effects
			(font
				(size 1.27 1.27)
			)
			(justify right bottom)
		)
	)
	(label "FB7"
		(at 186.69 93.98 180)
		(effects
			(font
				(size 1.27 1.27)
			)
			(justify right bottom)
		)
	)
	(label "1V2_SEN_+"
		(at 210.82 118.11 0)
		(effects
			(font
				(size 1.27 1.27)
			)
			(justify left bottom)
		)
	)
	(label "5V_local"
		(at 203.2 73.66 0)
		(effects
			(font
				(size 1.27 1.27)
			)
			(justify left bottom)
		)
	)
	(label "FB8"
		(at 334.01 104.14 0)
		(effects
			(font
				(size 1.27 1.27)
			)
			(justify left bottom)
		)
	)
	(label "3V3_SEN_+"
		(at 198.12 210.82 180)
		(effects
			(font
				(size 1.27 1.27)
			)
			(justify right bottom)
		)
	)
	(label "FB6"
		(at 303.53 104.14 0)
		(effects
			(font
				(size 1.27 1.27)
			)
			(justify left bottom)
		)
	)
	(label "FB5"
		(at 186.69 73.66 180)
		(effects
			(font
				(size 1.27 1.27)
			)
			(justify right bottom)
		)
	)
	(label "VDDQ_local"
		(at 203.2 91.44 0)
		(effects
			(font
				(size 1.27 1.27)
			)
			(justify left bottom)
		)
	)
	(label "3V3_SEN_+"
		(at 210.82 59.69 0)
		(effects
			(font
				(size 1.27 1.27)
			)
			(justify left bottom)
		)
	)
	(label "1V2_local"
		(at 203.2 110.49 0)
		(effects
			(font
				(size 1.27 1.27)
			)
			(justify left bottom)
		)
	)
	(global_label "PG3"
		(shape input)
		(at 144.78 99.06 180)
		(fields_autoplaced yes)
		(effects
			(font
				(size 1.27 1.27)
			)
			(justify right)
		)
		(property "Intersheetrefs" "${INTERSHEET_REFS}"
			(at 138.6995 99.06 0)
			(effects
				(font
					(size 1.27 1.27)
				)
				(justify right)
			)
		)
	)
	(hierarchical_label "PWR.SCL"
		(shape input)
		(at 147.32 214.63 180)
		(effects
			(font
				(size 1.27 1.27)
			)
			(justify right)
		)
	)
	(hierarchical_label "EN3"
		(shape input)
		(at 146.05 78.74 180)
		(effects
			(font
				(size 1.27 1.27)
			)
			(justify right)
		)
	)
	(hierarchical_label "QDCDC2_SCL"
		(shape input)
		(at 148.59 90.17 180)
		(effects
			(font
				(size 1.27 1.27)
			)
			(justify right)
		)
	)
	(hierarchical_label "PWR.SDA"
		(shape input)
		(at 148.59 87.63 180)
		(effects
			(font
				(size 1.27 1.27)
			)
			(justify right)
		)
	)
	(hierarchical_label "PWR.SDA"
		(shape input)
		(at 147.32 217.17 180)
		(effects
			(font
				(size 1.27 1.27)
			)
			(justify right)
		)
	)
	(symbol
		(lib_id "antmicroResistors0402:R_0R_0402")
		(at 309.88 101.6 90)
		(unit 1)
		(exclude_from_sim no)
		(in_bom yes)
		(on_board yes)
		(dnp no)
		(fields_autoplaced yes)
		(property "Reference" "R157"
			(at 312.42 97.7899 90)
			(effects
				(font
					(size 1.27 1.27)
				)
				(justify right)
			)
		)
		(property "Value" "R_0R_0402"
			(at 322.58 81.28 0)
			(effects
				(font
					(size 1.27 1.27)
					(thickness 0.15)
				)
				(justify left bottom)
				(hide yes)
			)
		)
		(property "Footprint" "antmicro-footprints:R_0402_1005Metric"
			(at 325.12 81.28 0)
			(effects
				(font
					(size 1.27 1.27)
					(thickness 0.15)
				)
				(justify left bottom)
				(hide yes)
			)
		)
		(property "Datasheet" "https://industrial.panasonic.com/cdbs/www-data/pdf/RDA0000/AOA0000C301.pdf"
			(at 327.66 81.28 0)
			(effects
				(font
					(size 1.27 1.27)
					(thickness 0.15)
				)
				(justify left bottom)
				(hide yes)
			)
		)
		(property "Description" ""
			(at 309.88 101.6 0)
			(effects
				(font
					(size 1.27 1.27)
				)
				(hide yes)
			)
		)
		(property "Manufacturer" "Panasonic"
			(at 332.74 81.28 0)
			(effects
				(font
					(size 1.27 1.27)
					(thickness 0.15)
				)
				(justify left bottom)
				(hide yes)
			)
		)
		(property "MPN" "ERJ2GE0R00X"
			(at 330.2 81.28 0)
			(effects
				(font
					(size 1.27 1.27)
					(thickness 0.15)
				)
				(justify left bottom)
				(hide yes)
			)
		)
		(property "Val" "0R"
			(at 312.42 100.3299 90)
			(effects
				(font
					(size 1.27 1.27)
					(thickness 0.15)
				)
				(justify right)
			)
		)
		(property "License" "Apache-2.0"
			(at 335.28 81.28 0)
			(effects
				(font
					(size 1.27 1.27)
					(thickness 0.15)
				)
				(justify left bottom)
				(hide yes)
			)
		)
		(property "Author" "Antmicro"
			(at 337.82 81.28 0)
			(effects
				(font
					(size 1.27 1.27)
					(thickness 0.15)
				)
				(justify left bottom)
				(hide yes)
			)
		)
		(property "Tolerance" "~"
			(at 320.04 81.28 0)
			(effects
				(font
					(size 1.27 1.27)
				)
				(justify left bottom)
				(hide yes)
			)
		)
		(property "Current" "1A"
			(at 312.42 101.5999 90)
			(effects
				(font
					(size 1.27 1.27)
					(thickness 0.15)
				)
				(justify right)
				(hide yes)
			)
		)
		(pin "1"
		)
		(pin "2"
		)
		(instances
			(project "data-center-rdimm-ddr5-tester"
				(path ""
					(reference "R157")
					(unit 1)
				)
			)
		)
	)
	(symbol
		(lib_id "antmicropower:GND")
		(at 203.2 85.09 0)
		(unit 1)
		(exclude_from_sim no)
		(in_bom yes)
		(on_board yes)
		(dnp no)
		(fields_autoplaced yes)
		(property "Reference" "#PWR0309"
			(at 203.2 91.44 0)
			(effects
				(font
					(size 1.27 1.27)
				)
				(hide yes)
			)
		)
		(property "Value" "GND"
			(at 201.295 89.535 0)
			(effects
				(font
					(size 1.27 1.27)
					(thickness 0.15)
				)
				(justify left bottom)
			)
		)
		(property "Footprint" ""
			(at 212.09 92.71 0)
			(effects
				(font
					(size 1.27 1.27)
					(thickness 0.15)
				)
				(justify left bottom)
				(hide yes)
			)
		)
		(property "Datasheet" ""
			(at 212.09 97.79 0)
			(effects
				(font
					(size 1.27 1.27)
					(thickness 0.15)
				)
				(justify left bottom)
				(hide yes)
			)
		)
		(property "Description" ""
			(at 203.2 85.09 0)
			(effects
				(font
					(size 1.27 1.27)
				)
				(hide yes)
			)
		)
		(property "Author" "Antmicro"
			(at 212.09 90.17 0)
			(effects
				(font
					(size 1.27 1.27)
					(thickness 0.15)
				)
				(justify left bottom)
				(hide yes)
			)
		)
		(property "License" "Apache-2.0"
			(at 212.09 92.71 0)
			(effects
				(font
					(size 1.27 1.27)
					(thickness 0.15)
				)
				(justify left bottom)
				(hide yes)
			)
		)
		(pin "1"
		)
		(instances
			(project "data-center-rdimm-ddr5-tester"
				(path ""
					(reference "#PWR0309")
					(unit 1)
				)
			)
		)
	)
	(symbol
		(lib_id "antmicropower:+3V3_AON")
		(at 104.14 207.01 0)
		(unit 1)
		(exclude_from_sim no)
		(in_bom yes)
		(on_board yes)
		(dnp no)
		(property "Reference" "#PWR0388"
			(at 104.14 210.82 0)
			(effects
				(font
					(size 1.27 1.27)
				)
				(hide yes)
			)
		)
		(property "Value" "+3V3_AON"
			(at 104.14 203.2 0)
			(effects
				(font
					(size 1.27 1.27)
				)
			)
		)
		(property "Footprint" ""
			(at 104.14 207.01 0)
			(effects
				(font
					(size 1.27 1.27)
				)
				(hide yes)
			)
		)
		(property "Datasheet" ""
			(at 104.14 207.01 0)
			(effects
				(font
					(size 1.27 1.27)
				)
				(hide yes)
			)
		)
		(property "Description" ""
			(at 104.14 207.01 0)
			(effects
				(font
					(size 1.27 1.27)
				)
				(hide yes)
			)
		)
		(pin "1"
		)
		(instances
			(project "data-center-rdimm-ddr5-tester"
				(path ""
					(reference "#PWR0388")
					(unit 1)
				)
			)
		)
	)
	(symbol
		(lib_id "antmicroResistors0402:R_0R_0402")
		(at 339.09 76.2 90)
		(unit 1)
		(exclude_from_sim no)
		(in_bom no)
		(on_board yes)
		(dnp yes)
		(property "Reference" "R167"
			(at 340.995 72.39 90)
			(effects
				(font
					(size 1.27 1.27)
				)
				(justify right)
			)
		)
		(property "Value" "R_0R_0402"
			(at 351.79 55.88 0)
			(effects
				(font
					(size 1.27 1.27)
					(thickness 0.15)
				)
				(justify left bottom)
				(hide yes)
			)
		)
		(property "Footprint" "antmicro-footprints:R_0402_1005Metric"
			(at 354.33 55.88 0)
			(effects
				(font
					(size 1.27 1.27)
					(thickness 0.15)
				)
				(justify left bottom)
				(hide yes)
			)
		)
		(property "Datasheet" "https://industrial.panasonic.com/cdbs/www-data/pdf/RDA0000/AOA0000C301.pdf"
			(at 356.87 55.88 0)
			(effects
				(font
					(size 1.27 1.27)
					(thickness 0.15)
				)
				(justify left bottom)
				(hide yes)
			)
		)
		(property "Description" ""
			(at 339.09 76.2 0)
			(effects
				(font
					(size 1.27 1.27)
				)
				(hide yes)
			)
		)
		(property "Manufacturer" "Panasonic"
			(at 361.95 55.88 0)
			(effects
				(font
					(size 1.27 1.27)
					(thickness 0.15)
				)
				(justify left bottom)
				(hide yes)
			)
		)
		(property "MPN" "ERJ2GE0R00X"
			(at 359.41 55.88 0)
			(effects
				(font
					(size 1.27 1.27)
					(thickness 0.15)
				)
				(justify left bottom)
				(hide yes)
			)
		)
		(property "Val" "0R"
			(at 340.995 74.93 90)
			(effects
				(font
					(size 1.27 1.27)
					(thickness 0.15)
				)
				(justify right)
			)
		)
		(property "License" "Apache-2.0"
			(at 364.49 55.88 0)
			(effects
				(font
					(size 1.27 1.27)
					(thickness 0.15)
				)
				(justify left bottom)
				(hide yes)
			)
		)
		(property "Author" "Antmicro"
			(at 367.03 55.88 0)
			(effects
				(font
					(size 1.27 1.27)
					(thickness 0.15)
				)
				(justify left bottom)
				(hide yes)
			)
		)
		(property "Tolerance" "~"
			(at 349.25 55.88 0)
			(effects
				(font
					(size 1.27 1.27)
				)
				(justify left bottom)
				(hide yes)
			)
		)
		(property "Current" "1A"
			(at 340.995 77.4699 90)
			(effects
				(font
					(size 1.27 1.27)
					(thickness 0.15)
				)
				(justify right)
				(hide yes)
			)
		)
		(pin "1"
		)
		(pin "2"
		)
		(instances
			(project "data-center-rdimm-ddr5-tester"
				(path ""
					(reference "R167")
					(unit 1)
				)
			)
		)
	)
	(symbol
		(lib_id "antmicroResistors0402:R_0R_0402")
		(at 175.26 210.82 0)
		(unit 1)
		(exclude_from_sim no)
		(in_bom yes)
		(on_board yes)
		(dnp no)
		(property "Reference" "R209"
			(at 182.88 209.55 0)
			(effects
				(font
					(size 1.27 1.27)
					(thickness 0.15)
				)
			)
		)
		(property "Value" "R_0R_0402"
			(at 195.58 223.52 0)
			(effects
				(font
					(size 1.27 1.27)
					(thickness 0.15)
				)
				(justify left bottom)
				(hide yes)
			)
		)
		(property "Footprint" "antmicro-footprints:R_0402_1005Metric"
			(at 195.58 226.06 0)
			(effects
				(font
					(size 1.27 1.27)
					(thickness 0.15)
				)
				(justify left bottom)
				(hide yes)
			)
		)
		(property "Datasheet" "https://industrial.panasonic.com/cdbs/www-data/pdf/RDA0000/AOA0000C301.pdf"
			(at 195.58 228.6 0)
			(effects
				(font
					(size 1.27 1.27)
					(thickness 0.15)
				)
				(justify left bottom)
				(hide yes)
			)
		)
		(property "Description" ""
			(at 175.26 210.82 0)
			(effects
				(font
					(size 1.27 1.27)
				)
				(hide yes)
			)
		)
		(property "MPN" "ERJ2GE0R00X"
			(at 195.58 231.14 0)
			(effects
				(font
					(size 1.27 1.27)
					(thickness 0.15)
				)
				(justify left bottom)
				(hide yes)
			)
		)
		(property "Manufacturer" "Panasonic"
			(at 195.58 233.68 0)
			(effects
				(font
					(size 1.27 1.27)
					(thickness 0.15)
				)
				(justify left bottom)
				(hide yes)
			)
		)
		(property "License" "Apache-2.0"
			(at 195.58 236.22 0)
			(effects
				(font
					(size 1.27 1.27)
					(thickness 0.15)
				)
				(justify left bottom)
				(hide yes)
			)
		)
		(property "Author" "Antmicro"
			(at 195.58 238.76 0)
			(effects
				(font
					(size 1.27 1.27)
					(thickness 0.15)
				)
				(justify left bottom)
				(hide yes)
			)
		)
		(property "Val" "0R"
			(at 181.61 212.09 0)
			(effects
				(font
					(size 1.27 1.27)
					(thickness 0.15)
				)
			)
		)
		(property "Tolerance" "~"
			(at 195.58 220.98 0)
			(effects
				(font
					(size 1.27 1.27)
				)
				(justify left bottom)
				(hide yes)
			)
		)
		(property "Current" "1A"
			(at 195.58 241.3 0)
			(effects
				(font
					(size 1.27 1.27)
					(thickness 0.15)
				)
				(justify left bottom)
				(hide yes)
			)
		)
		(pin "2"
		)
		(pin "1"
		)
		(instances
			(project "data-center-rdimm-ddr5-tester"
				(path ""
					(reference "R209")
					(unit 1)
				)
			)
		)
	)
	(symbol
		(lib_id "antmicroTestPoints:TP_1mm_SMD")
		(at 251.46 91.44 0)
		(unit 1)
		(exclude_from_sim no)
		(in_bom no)
		(on_board yes)
		(dnp no)
		(fields_autoplaced yes)
		(property "Reference" "TP9"
			(at 256.032 91.8738 0)
			(effects
				(font
					(size 1.27 1.27)
				)
				(justify left)
			)
		)
		(property "Value" "TP_1mm_SMD"
			(at 266.7 99.06 0)
			(effects
				(font
					(size 1.27 1.27)
					(thickness 0.15)
				)
				(justify left bottom)
				(hide yes)
			)
		)
		(property "Footprint" "antmicro-footprints:TP_SMD_1mm"
			(at 266.7 101.6 0)
			(effects
				(font
					(size 1.27 1.27)
					(thickness 0.15)
				)
				(justify left bottom)
				(hide yes)
			)
		)
		(property "Datasheet" ""
			(at 266.7 104.14 0)
			(effects
				(font
					(size 1.27 1.27)
					(thickness 0.15)
				)
				(justify left bottom)
				(hide yes)
			)
		)
		(property "Description" ""
			(at 251.46 91.44 0)
			(effects
				(font
					(size 1.27 1.27)
				)
				(hide yes)
			)
		)
		(property "MPN" ""
			(at 251.46 91.44 0)
			(effects
				(font
					(size 1.27 1.27)
				)
				(hide yes)
			)
		)
		(property "Manufacturer" ""
			(at 251.46 91.44 0)
			(effects
				(font
					(size 1.27 1.27)
				)
				(hide yes)
			)
		)
		(property "Author" "Antmicro"
			(at 266.7 106.68 0)
			(effects
				(font
					(size 1.27 1.27)
					(thickness 0.15)
				)
				(justify left bottom)
				(hide yes)
			)
		)
		(property "License" "Apache-2.0"
			(at 266.7 109.22 0)
			(effects
				(font
					(size 1.27 1.27)
					(thickness 0.15)
				)
				(justify left bottom)
				(hide yes)
			)
		)
		(pin "1"
		)
		(instances
			(project "data-center-rdimm-ddr5-tester"
				(path ""
					(reference "TP9")
					(unit 1)
				)
			)
		)
	)
	(symbol
		(lib_id "antmicroResistors0402:R_0R_0402")
		(at 308.61 76.2 90)
		(unit 1)
		(exclude_from_sim no)
		(in_bom no)
		(on_board yes)
		(dnp yes)
		(property "Reference" "R156"
			(at 311.15 72.39 90)
			(effects
				(font
					(size 1.27 1.27)
				)
				(justify right)
			)
		)
		(property "Value" "R_0R_0402"
			(at 321.31 55.88 0)
			(effects
				(font
					(size 1.27 1.27)
					(thickness 0.15)
				)
				(justify left bottom)
				(hide yes)
			)
		)
		(property "Footprint" "antmicro-footprints:R_0402_1005Metric"
			(at 323.85 55.88 0)
			(effects
				(font
					(size 1.27 1.27)
					(thickness 0.15)
				)
				(justify left bottom)
				(hide yes)
			)
		)
		(property "Datasheet" "https://industrial.panasonic.com/cdbs/www-data/pdf/RDA0000/AOA0000C301.pdf"
			(at 326.39 55.88 0)
			(effects
				(font
					(size 1.27 1.27)
					(thickness 0.15)
				)
				(justify left bottom)
				(hide yes)
			)
		)
		(property "Description" ""
			(at 308.61 76.2 0)
			(effects
				(font
					(size 1.27 1.27)
				)
				(hide yes)
			)
		)
		(property "Manufacturer" "Panasonic"
			(at 331.47 55.88 0)
			(effects
				(font
					(size 1.27 1.27)
					(thickness 0.15)
				)
				(justify left bottom)
				(hide yes)
			)
		)
		(property "MPN" "ERJ2GE0R00X"
			(at 328.93 55.88 0)
			(effects
				(font
					(size 1.27 1.27)
					(thickness 0.15)
				)
				(justify left bottom)
				(hide yes)
			)
		)
		(property "Val" "0R"
			(at 311.15 74.93 90)
			(effects
				(font
					(size 1.27 1.27)
					(thickness 0.15)
				)
				(justify right)
			)
		)
		(property "License" "Apache-2.0"
			(at 334.01 55.88 0)
			(effects
				(font
					(size 1.27 1.27)
					(thickness 0.15)
				)
				(justify left bottom)
				(hide yes)
			)
		)
		(property "Author" "Antmicro"
			(at 336.55 55.88 0)
			(effects
				(font
					(size 1.27 1.27)
					(thickness 0.15)
				)
				(justify left bottom)
				(hide yes)
			)
		)
		(property "Tolerance" "~"
			(at 318.77 55.88 0)
			(effects
				(font
					(size 1.27 1.27)
				)
				(justify left bottom)
				(hide yes)
			)
		)
		(property "Current" "1A"
			(at 311.15 77.4699 90)
			(effects
				(font
					(size 1.27 1.27)
					(thickness 0.15)
				)
				(justify right)
				(hide yes)
			)
		)
		(pin "1"
		)
		(pin "2"
		)
		(instances
			(project "data-center-rdimm-ddr5-tester"
				(path ""
					(reference "R156")
					(unit 1)
				)
			)
		)
	)
	(symbol
		(lib_id "antmicroCapacitors0603:C_22u_0603")
		(at 203.2 81.28 90)
		(unit 1)
		(exclude_from_sim no)
		(in_bom yes)
		(on_board yes)
		(dnp no)
		(property "Reference" "C191"
			(at 203.835 76.835 90)
			(effects
				(font
					(size 1.27 1.27)
				)
				(justify right)
			)
		)
		(property "Value" "C_22u_0603"
			(at 213.36 60.96 0)
			(effects
				(font
					(size 1.27 1.27)
					(thickness 0.15)
				)
				(justify left bottom)
				(hide yes)
			)
		)
		(property "Footprint" "antmicro-footprints:C_0603_1608Metric"
			(at 215.9 60.96 0)
			(effects
				(font
					(size 1.27 1.27)
					(thickness 0.15)
				)
				(justify left bottom)
				(hide yes)
			)
		)
		(property "Datasheet" "https://www.murata.com/products/productdetail?partno=GRM188R60J226MEA0%23"
			(at 218.44 60.96 0)
			(effects
				(font
					(size 1.27 1.27)
					(thickness 0.15)
				)
				(justify left bottom)
				(hide yes)
			)
		)
		(property "Description" ""
			(at 203.2 81.28 0)
			(effects
				(font
					(size 1.27 1.27)
				)
				(hide yes)
			)
		)
		(property "Manufacturer" "Murata"
			(at 223.52 60.96 0)
			(effects
				(font
					(size 1.27 1.27)
					(thickness 0.15)
				)
				(justify left bottom)
				(hide yes)
			)
		)
		(property "MPN" "GRM188R60J226MEA0D"
			(at 220.98 60.96 0)
			(effects
				(font
					(size 1.27 1.27)
					(thickness 0.15)
				)
				(justify left bottom)
				(hide yes)
			)
		)
		(property "Val" "22u"
			(at 203.835 80.645 90)
			(effects
				(font
					(size 1.27 1.27)
					(thickness 0.15)
				)
				(justify right)
			)
		)
		(property "License" "Apache-2.0"
			(at 226.06 60.96 0)
			(effects
				(font
					(size 1.27 1.27)
					(thickness 0.15)
				)
				(justify left bottom)
				(hide yes)
			)
		)
		(property "Author" "Antmicro"
			(at 228.6 60.96 0)
			(effects
				(font
					(size 1.27 1.27)
					(thickness 0.15)
				)
				(justify left bottom)
				(hide yes)
			)
		)
		(property "Voltage" ""
			(at 231.14 60.96 0)
			(effects
				(font
					(size 1.27 1.27)
				)
				(justify left bottom)
				(hide yes)
			)
		)
		(property "Dielectric" ""
			(at 233.68 60.96 0)
			(effects
				(font
					(size 1.27 1.27)
				)
				(justify left bottom)
				(hide yes)
			)
		)
		(pin "1"
		)
		(pin "2"
		)
		(instances
			(project "data-center-rdimm-ddr5-tester"
				(path ""
					(reference "C191")
					(unit 1)
				)
			)
		)
	)
	(symbol
		(lib_id "antmicroShuntsJumpers:Net-Tie_P0.127mm")
		(at 222.25 58.42 90)
		(unit 1)
		(exclude_from_sim no)
		(in_bom no)
		(on_board yes)
		(dnp no)
		(fields_autoplaced yes)
		(property "Reference" "NT5"
			(at 220.98 58.42 0)
			(effects
				(font
					(size 1.27 1.27)
				)
				(hide yes)
			)
		)
		(property "Value" "Net-Tie_P0.127mm"
			(at 229.87 36.83 0)
			(effects
				(font
					(size 1.27 1.27)
					(thickness 0.15)
				)
				(justify left bottom)
				(hide yes)
			)
		)
		(property "Footprint" "antmicro-footprints:NetTie-2_SMD_Pad0.127mm"
			(at 234.95 36.83 0)
			(effects
				(font
					(size 1.27 1.27)
					(thickness 0.15)
				)
				(justify left bottom)
				(hide yes)
			)
		)
		(property "Datasheet" ""
			(at 237.49 36.83 0)
			(effects
				(font
					(size 1.27 1.27)
					(thickness 0.15)
				)
				(justify left bottom)
				(hide yes)
			)
		)
		(property "Description" ""
			(at 222.25 58.42 0)
			(effects
				(font
					(size 1.27 1.27)
				)
				(hide yes)
			)
		)
		(property "MPN" ""
			(at 232.41 36.83 0)
			(effects
				(font
					(size 1.27 1.27)
					(thickness 0.15)
				)
				(justify left bottom)
			)
		)
		(property "Manufacturer" ""
			(at 240.03 36.83 0)
			(effects
				(font
					(size 1.27 1.27)
					(thickness 0.15)
				)
				(justify left bottom)
				(hide yes)
			)
		)
		(property "Author" "Antmicro"
			(at 242.57 36.83 0)
			(effects
				(font
					(size 1.27 1.27)
					(thickness 0.15)
				)
				(justify left bottom)
				(hide yes)
			)
		)
		(property "License" "Apache-2.0"
			(at 245.11 36.83 0)
			(effects
				(font
					(size 1.27 1.27)
					(thickness 0.15)
				)
				(justify left bottom)
				(hide yes)
			)
		)
		(pin "1"
		)
		(pin "2"
		)
		(instances
			(project "data-center-rdimm-ddr5-tester"
				(path ""
					(reference "NT5")
					(unit 1)
				)
			)
		)
	)
	(symbol
		(lib_id "antmicroShuntsJumpers:Net-Tie_P0.127mm")
		(at 229.87 116.84 90)
		(unit 1)
		(exclude_from_sim no)
		(in_bom no)
		(on_board yes)
		(dnp no)
		(fields_autoplaced yes)
		(property "Reference" "NT16"
			(at 228.6 116.84 0)
			(effects
				(font
					(size 1.27 1.27)
				)
				(hide yes)
			)
		)
		(property "Value" "Net-Tie_P0.127mm"
			(at 237.49 95.25 0)
			(effects
				(font
					(size 1.27 1.27)
					(thickness 0.15)
				)
				(justify left bottom)
				(hide yes)
			)
		)
		(property "Footprint" "antmicro-footprints:NetTie-2_SMD_Pad0.127mm"
			(at 242.57 95.25 0)
			(effects
				(font
					(size 1.27 1.27)
					(thickness 0.15)
				)
				(justify left bottom)
				(hide yes)
			)
		)
		(property "Datasheet" ""
			(at 245.11 95.25 0)
			(effects
				(font
					(size 1.27 1.27)
					(thickness 0.15)
				)
				(justify left bottom)
				(hide yes)
			)
		)
		(property "Description" ""
			(at 229.87 116.84 0)
			(effects
				(font
					(size 1.27 1.27)
				)
				(hide yes)
			)
		)
		(property "MPN" ""
			(at 240.03 95.25 0)
			(effects
				(font
					(size 1.27 1.27)
					(thickness 0.15)
				)
				(justify left bottom)
			)
		)
		(property "Manufacturer" ""
			(at 247.65 95.25 0)
			(effects
				(font
					(size 1.27 1.27)
					(thickness 0.15)
				)
				(justify left bottom)
				(hide yes)
			)
		)
		(property "Author" "Antmicro"
			(at 250.19 95.25 0)
			(effects
				(font
					(size 1.27 1.27)
					(thickness 0.15)
				)
				(justify left bottom)
				(hide yes)
			)
		)
		(property "License" "Apache-2.0"
			(at 252.73 95.25 0)
			(effects
				(font
					(size 1.27 1.27)
					(thickness 0.15)
				)
				(justify left bottom)
				(hide yes)
			)
		)
		(pin "1"
		)
		(pin "2"
		)
		(instances
			(project "data-center-rdimm-ddr5-tester"
				(path ""
					(reference "NT16")
					(unit 1)
				)
			)
		)
	)
	(symbol
		(lib_id "antmicroShuntsJumpers:Net-Tie_P0.127mm")
		(at 229.87 97.79 90)
		(unit 1)
		(exclude_from_sim no)
		(in_bom no)
		(on_board yes)
		(dnp no)
		(fields_autoplaced yes)
		(property "Reference" "NT15"
			(at 228.6 97.79 0)
			(effects
				(font
					(size 1.27 1.27)
				)
				(hide yes)
			)
		)
		(property "Value" "Net-Tie_P0.127mm"
			(at 237.49 76.2 0)
			(effects
				(font
					(size 1.27 1.27)
					(thickness 0.15)
				)
				(justify left bottom)
				(hide yes)
			)
		)
		(property "Footprint" "antmicro-footprints:NetTie-2_SMD_Pad0.127mm"
			(at 242.57 76.2 0)
			(effects
				(font
					(size 1.27 1.27)
					(thickness 0.15)
				)
				(justify left bottom)
				(hide yes)
			)
		)
		(property "Datasheet" ""
			(at 245.11 76.2 0)
			(effects
				(font
					(size 1.27 1.27)
					(thickness 0.15)
				)
				(justify left bottom)
				(hide yes)
			)
		)
		(property "Description" ""
			(at 229.87 97.79 0)
			(effects
				(font
					(size 1.27 1.27)
				)
				(hide yes)
			)
		)
		(property "MPN" ""
			(at 240.03 76.2 0)
			(effects
				(font
					(size 1.27 1.27)
					(thickness 0.15)
				)
				(justify left bottom)
			)
		)
		(property "Manufacturer" ""
			(at 247.65 76.2 0)
			(effects
				(font
					(size 1.27 1.27)
					(thickness 0.15)
				)
				(justify left bottom)
				(hide yes)
			)
		)
		(property "Author" "Antmicro"
			(at 250.19 76.2 0)
			(effects
				(font
					(size 1.27 1.27)
					(thickness 0.15)
				)
				(justify left bottom)
				(hide yes)
			)
		)
		(property "License" "Apache-2.0"
			(at 252.73 76.2 0)
			(effects
				(font
					(size 1.27 1.27)
					(thickness 0.15)
				)
				(justify left bottom)
				(hide yes)
			)
		)
		(pin "1"
		)
		(pin "2"
		)
		(instances
			(project "data-center-rdimm-ddr5-tester"
				(path ""
					(reference "NT15")
					(unit 1)
				)
			)
		)
	)
	(symbol
		(lib_id "antmicropower:PWR_FLAG")
		(at 241.3 50.8 0)
		(unit 1)
		(exclude_from_sim no)
		(in_bom yes)
		(on_board yes)
		(dnp no)
		(fields_autoplaced yes)
		(property "Reference" "#FLG012"
			(at 241.3 48.895 0)
			(effects
				(font
					(size 1.27 1.27)
				)
				(hide yes)
			)
		)
		(property "Value" "PWR_FLAG"
			(at 241.3 47.2242 0)
			(effects
				(font
					(size 1.27 1.27)
				)
			)
		)
		(property "Footprint" ""
			(at 241.3 50.8 0)
			(effects
				(font
					(size 1.27 1.27)
				)
				(hide yes)
			)
		)
		(property "Datasheet" ""
			(at 241.3 50.8 0)
			(effects
				(font
					(size 1.27 1.27)
				)
				(hide yes)
			)
		)
		(property "Description" ""
			(at 241.3 50.8 0)
			(effects
				(font
					(size 1.27 1.27)
				)
				(hide yes)
			)
		)
		(pin "1"
		)
		(instances
			(project "data-center-rdimm-ddr5-tester"
				(path ""
					(reference "#FLG012")
					(unit 1)
				)
			)
		)
	)
	(symbol
		(lib_id "antmicropower:+1V2")
		(at 250.19 109.22 0)
		(unit 1)
		(exclude_from_sim no)
		(in_bom yes)
		(on_board yes)
		(dnp no)
		(property "Reference" "#PWR0325"
			(at 250.19 113.03 0)
			(effects
				(font
					(size 1.27 1.27)
				)
				(hide yes)
			)
		)
		(property "Value" "+1V2"
			(at 250.19 105.664 0)
			(effects
				(font
					(size 1.27 1.27)
				)
			)
		)
		(property "Footprint" ""
			(at 250.19 109.22 0)
			(effects
				(font
					(size 1.27 1.27)
				)
				(hide yes)
			)
		)
		(property "Datasheet" ""
			(at 250.19 109.22 0)
			(effects
				(font
					(size 1.27 1.27)
				)
				(hide yes)
			)
		)
		(property "Description" ""
			(at 250.19 109.22 0)
			(effects
				(font
					(size 1.27 1.27)
				)
				(hide yes)
			)
		)
		(pin "1"
		)
		(instances
			(project "data-center-rdimm-ddr5-tester"
				(path ""
					(reference "#PWR0325")
					(unit 1)
				)
			)
		)
	)
	(symbol
		(lib_id "antmicroTestPoints:TP_1mm_SMD")
		(at 252.73 52.07 0)
		(unit 1)
		(exclude_from_sim no)
		(in_bom no)
		(on_board yes)
		(dnp no)
		(fields_autoplaced yes)
		(property "Reference" "TP12"
			(at 257.302 52.5038 0)
			(effects
				(font
					(size 1.27 1.27)
				)
				(justify left)
			)
		)
		(property "Value" "TP_1mm_SMD"
			(at 267.97 59.69 0)
			(effects
				(font
					(size 1.27 1.27)
					(thickness 0.15)
				)
				(justify left bottom)
				(hide yes)
			)
		)
		(property "Footprint" "antmicro-footprints:TP_SMD_1mm"
			(at 267.97 62.23 0)
			(effects
				(font
					(size 1.27 1.27)
					(thickness 0.15)
				)
				(justify left bottom)
				(hide yes)
			)
		)
		(property "Datasheet" ""
			(at 267.97 64.77 0)
			(effects
				(font
					(size 1.27 1.27)
					(thickness 0.15)
				)
				(justify left bottom)
				(hide yes)
			)
		)
		(property "Description" ""
			(at 252.73 52.07 0)
			(effects
				(font
					(size 1.27 1.27)
				)
				(hide yes)
			)
		)
		(property "MPN" ""
			(at 252.73 52.07 0)
			(effects
				(font
					(size 1.27 1.27)
				)
				(hide yes)
			)
		)
		(property "Manufacturer" ""
			(at 252.73 52.07 0)
			(effects
				(font
					(size 1.27 1.27)
				)
				(hide yes)
			)
		)
		(property "Author" "Antmicro"
			(at 267.97 67.31 0)
			(effects
				(font
					(size 1.27 1.27)
					(thickness 0.15)
				)
				(justify left bottom)
				(hide yes)
			)
		)
		(property "License" "Apache-2.0"
			(at 267.97 69.85 0)
			(effects
				(font
					(size 1.27 1.27)
					(thickness 0.15)
				)
				(justify left bottom)
				(hide yes)
			)
		)
		(pin "1"
		)
		(instances
			(project "data-center-rdimm-ddr5-tester"
				(path ""
					(reference "TP12")
					(unit 1)
				)
			)
		)
	)
	(symbol
		(lib_id "antmicropower:PWR_FLAG")
		(at 242.57 109.22 0)
		(unit 1)
		(exclude_from_sim no)
		(in_bom yes)
		(on_board yes)
		(dnp no)
		(fields_autoplaced yes)
		(property "Reference" "#FLG015"
			(at 242.57 107.315 0)
			(effects
				(font
					(size 1.27 1.27)
				)
				(hide yes)
			)
		)
		(property "Value" "PWR_FLAG"
			(at 242.57 105.6442 0)
			(effects
				(font
					(size 1.27 1.27)
				)
			)
		)
		(property "Footprint" ""
			(at 242.57 109.22 0)
			(effects
				(font
					(size 1.27 1.27)
				)
				(hide yes)
			)
		)
		(property "Datasheet" ""
			(at 242.57 109.22 0)
			(effects
				(font
					(size 1.27 1.27)
				)
				(hide yes)
			)
		)
		(property "Description" ""
			(at 242.57 109.22 0)
			(effects
				(font
					(size 1.27 1.27)
				)
				(hide yes)
			)
		)
		(pin "1"
		)
		(instances
			(project "data-center-rdimm-ddr5-tester"
				(path ""
					(reference "#FLG015")
					(unit 1)
				)
			)
		)
	)
	(symbol
		(lib_id "antmicropower:GND")
		(at 309.88 115.57 0)
		(unit 1)
		(exclude_from_sim no)
		(in_bom yes)
		(on_board yes)
		(dnp no)
		(fields_autoplaced yes)
		(property "Reference" "#PWR0338"
			(at 309.88 121.92 0)
			(effects
				(font
					(size 1.27 1.27)
				)
				(hide yes)
			)
		)
		(property "Value" "GND"
			(at 307.975 120.015 0)
			(effects
				(font
					(size 1.27 1.27)
					(thickness 0.15)
				)
				(justify left bottom)
			)
		)
		(property "Footprint" ""
			(at 318.77 123.19 0)
			(effects
				(font
					(size 1.27 1.27)
					(thickness 0.15)
				)
				(justify left bottom)
				(hide yes)
			)
		)
		(property "Datasheet" ""
			(at 318.77 128.27 0)
			(effects
				(font
					(size 1.27 1.27)
					(thickness 0.15)
				)
				(justify left bottom)
				(hide yes)
			)
		)
		(property "Description" ""
			(at 309.88 115.57 0)
			(effects
				(font
					(size 1.27 1.27)
				)
				(hide yes)
			)
		)
		(property "Author" "Antmicro"
			(at 318.77 120.65 0)
			(effects
				(font
					(size 1.27 1.27)
					(thickness 0.15)
				)
				(justify left bottom)
				(hide yes)
			)
		)
		(property "License" "Apache-2.0"
			(at 318.77 123.19 0)
			(effects
				(font
					(size 1.27 1.27)
					(thickness 0.15)
				)
				(justify left bottom)
				(hide yes)
			)
		)
		(pin "1"
		)
		(instances
			(project "data-center-rdimm-ddr5-tester"
				(path ""
					(reference "#PWR0338")
					(unit 1)
				)
			)
		)
	)
	(symbol
		(lib_id "antmicroCapacitors0603:C_22u_0603")
		(at 203.2 59.69 90)
		(unit 1)
		(exclude_from_sim no)
		(in_bom yes)
		(on_board yes)
		(dnp no)
		(property "Reference" "C190"
			(at 203.835 55.245 90)
			(effects
				(font
					(size 1.27 1.27)
				)
				(justify right)
			)
		)
		(property "Value" "C_22u_0603"
			(at 213.36 39.37 0)
			(effects
				(font
					(size 1.27 1.27)
					(thickness 0.15)
				)
				(justify left bottom)
				(hide yes)
			)
		)
		(property "Footprint" "antmicro-footprints:C_0603_1608Metric"
			(at 215.9 39.37 0)
			(effects
				(font
					(size 1.27 1.27)
					(thickness 0.15)
				)
				(justify left bottom)
				(hide yes)
			)
		)
		(property "Datasheet" "https://www.murata.com/products/productdetail?partno=GRM188R60J226MEA0%23"
			(at 218.44 39.37 0)
			(effects
				(font
					(size 1.27 1.27)
					(thickness 0.15)
				)
				(justify left bottom)
				(hide yes)
			)
		)
		(property "Description" ""
			(at 203.2 59.69 0)
			(effects
				(font
					(size 1.27 1.27)
				)
				(hide yes)
			)
		)
		(property "Manufacturer" "Murata"
			(at 223.52 39.37 0)
			(effects
				(font
					(size 1.27 1.27)
					(thickness 0.15)
				)
				(justify left bottom)
				(hide yes)
			)
		)
		(property "MPN" "GRM188R60J226MEA0D"
			(at 220.98 39.37 0)
			(effects
				(font
					(size 1.27 1.27)
					(thickness 0.15)
				)
				(justify left bottom)
				(hide yes)
			)
		)
		(property "Val" "22u"
			(at 203.835 59.055 90)
			(effects
				(font
					(size 1.27 1.27)
					(thickness 0.15)
				)
				(justify right)
			)
		)
		(property "License" "Apache-2.0"
			(at 226.06 39.37 0)
			(effects
				(font
					(size 1.27 1.27)
					(thickness 0.15)
				)
				(justify left bottom)
				(hide yes)
			)
		)
		(property "Author" "Antmicro"
			(at 228.6 39.37 0)
			(effects
				(font
					(size 1.27 1.27)
					(thickness 0.15)
				)
				(justify left bottom)
				(hide yes)
			)
		)
		(property "Voltage" ""
			(at 231.14 39.37 0)
			(effects
				(font
					(size 1.27 1.27)
				)
				(justify left bottom)
				(hide yes)
			)
		)
		(property "Dielectric" ""
			(at 233.68 39.37 0)
			(effects
				(font
					(size 1.27 1.27)
				)
				(justify left bottom)
				(hide yes)
			)
		)
		(pin "1"
		)
		(pin "2"
		)
		(instances
			(project "data-center-rdimm-ddr5-tester"
				(path ""
					(reference "C190")
					(unit 1)
				)
			)
		)
	)
	(symbol
		(lib_id "antmicroResistors0402:R_0R_0402")
		(at 175.26 223.52 0)
		(unit 1)
		(exclude_from_sim no)
		(in_bom yes)
		(on_board yes)
		(dnp no)
		(property "Reference" "R213"
			(at 182.88 222.25 0)
			(effects
				(font
					(size 1.27 1.27)
					(thickness 0.15)
				)
			)
		)
		(property "Value" "R_0R_0402"
			(at 195.58 236.22 0)
			(effects
				(font
					(size 1.27 1.27)
					(thickness 0.15)
				)
				(justify left bottom)
				(hide yes)
			)
		)
		(property "Footprint" "antmicro-footprints:R_0402_1005Metric"
			(at 195.58 238.76 0)
			(effects
				(font
					(size 1.27 1.27)
					(thickness 0.15)
				)
				(justify left bottom)
				(hide yes)
			)
		)
		(property "Datasheet" "https://industrial.panasonic.com/cdbs/www-data/pdf/RDA0000/AOA0000C301.pdf"
			(at 195.58 241.3 0)
			(effects
				(font
					(size 1.27 1.27)
					(thickness 0.15)
				)
				(justify left bottom)
				(hide yes)
			)
		)
		(property "Description" ""
			(at 175.26 223.52 0)
			(effects
				(font
					(size 1.27 1.27)
				)
				(hide yes)
			)
		)
		(property "MPN" "ERJ2GE0R00X"
			(at 195.58 243.84 0)
			(effects
				(font
					(size 1.27 1.27)
					(thickness 0.15)
				)
				(justify left bottom)
				(hide yes)
			)
		)
		(property "Manufacturer" "Panasonic"
			(at 195.58 246.38 0)
			(effects
				(font
					(size 1.27 1.27)
					(thickness 0.15)
				)
				(justify left bottom)
				(hide yes)
			)
		)
		(property "License" "Apache-2.0"
			(at 195.58 248.92 0)
			(effects
				(font
					(size 1.27 1.27)
					(thickness 0.15)
				)
				(justify left bottom)
				(hide yes)
			)
		)
		(property "Author" "Antmicro"
			(at 195.58 251.46 0)
			(effects
				(font
					(size 1.27 1.27)
					(thickness 0.15)
				)
				(justify left bottom)
				(hide yes)
			)
		)
		(property "Val" "0R"
			(at 181.61 224.79 0)
			(effects
				(font
					(size 1.27 1.27)
					(thickness 0.15)
				)
			)
		)
		(property "Tolerance" "~"
			(at 195.58 233.68 0)
			(effects
				(font
					(size 1.27 1.27)
				)
				(justify left bottom)
				(hide yes)
			)
		)
		(property "Current" "1A"
			(at 195.58 254 0)
			(effects
				(font
					(size 1.27 1.27)
					(thickness 0.15)
				)
				(justify left bottom)
				(hide yes)
			)
		)
		(pin "2"
		)
		(pin "1"
		)
		(instances
			(project "data-center-rdimm-ddr5-tester"
				(path ""
					(reference "R213")
					(unit 1)
				)
			)
		)
	)
	(symbol
		(lib_id "antmicroShuntsJumpers:Net-Tie_P0.127mm")
		(at 222.25 80.01 90)
		(unit 1)
		(exclude_from_sim no)
		(in_bom no)
		(on_board yes)
		(dnp no)
		(fields_autoplaced yes)
		(property "Reference" "NT6"
			(at 220.98 80.01 0)
			(effects
				(font
					(size 1.27 1.27)
				)
				(hide yes)
			)
		)
		(property "Value" "Net-Tie_P0.127mm"
			(at 229.87 58.42 0)
			(effects
				(font
					(size 1.27 1.27)
					(thickness 0.15)
				)
				(justify left bottom)
				(hide yes)
			)
		)
		(property "Footprint" "antmicro-footprints:NetTie-2_SMD_Pad0.127mm"
			(at 234.95 58.42 0)
			(effects
				(font
					(size 1.27 1.27)
					(thickness 0.15)
				)
				(justify left bottom)
				(hide yes)
			)
		)
		(property "Datasheet" ""
			(at 237.49 58.42 0)
			(effects
				(font
					(size 1.27 1.27)
					(thickness 0.15)
				)
				(justify left bottom)
				(hide yes)
			)
		)
		(property "Description" ""
			(at 222.25 80.01 0)
			(effects
				(font
					(size 1.27 1.27)
				)
				(hide yes)
			)
		)
		(property "MPN" ""
			(at 232.41 58.42 0)
			(effects
				(font
					(size 1.27 1.27)
					(thickness 0.15)
				)
				(justify left bottom)
			)
		)
		(property "Manufacturer" ""
			(at 240.03 58.42 0)
			(effects
				(font
					(size 1.27 1.27)
					(thickness 0.15)
				)
				(justify left bottom)
				(hide yes)
			)
		)
		(property "Author" "Antmicro"
			(at 242.57 58.42 0)
			(effects
				(font
					(size 1.27 1.27)
					(thickness 0.15)
				)
				(justify left bottom)
				(hide yes)
			)
		)
		(property "License" "Apache-2.0"
			(at 245.11 58.42 0)
			(effects
				(font
					(size 1.27 1.27)
					(thickness 0.15)
				)
				(justify left bottom)
				(hide yes)
			)
		)
		(pin "1"
		)
		(pin "2"
		)
		(instances
			(project "data-center-rdimm-ddr5-tester"
				(path ""
					(reference "NT6")
					(unit 1)
				)
			)
		)
	)
	(symbol
		(lib_id "antmicropower:GND")
		(at 203.2 102.87 0)
		(unit 1)
		(exclude_from_sim no)
		(in_bom yes)
		(on_board yes)
		(dnp no)
		(fields_autoplaced yes)
		(property "Reference" "#PWR0310"
			(at 203.2 109.22 0)
			(effects
				(font
					(size 1.27 1.27)
				)
				(hide yes)
			)
		)
		(property "Value" "GND"
			(at 201.295 107.315 0)
			(effects
				(font
					(size 1.27 1.27)
					(thickness 0.15)
				)
				(justify left bottom)
			)
		)
		(property "Footprint" ""
			(at 212.09 110.49 0)
			(effects
				(font
					(size 1.27 1.27)
					(thickness 0.15)
				)
				(justify left bottom)
				(hide yes)
			)
		)
		(property "Datasheet" ""
			(at 212.09 115.57 0)
			(effects
				(font
					(size 1.27 1.27)
					(thickness 0.15)
				)
				(justify left bottom)
				(hide yes)
			)
		)
		(property "Description" ""
			(at 203.2 102.87 0)
			(effects
				(font
					(size 1.27 1.27)
				)
				(hide yes)
			)
		)
		(property "Author" "Antmicro"
			(at 212.09 107.95 0)
			(effects
				(font
					(size 1.27 1.27)
					(thickness 0.15)
				)
				(justify left bottom)
				(hide yes)
			)
		)
		(property "License" "Apache-2.0"
			(at 212.09 110.49 0)
			(effects
				(font
					(size 1.27 1.27)
					(thickness 0.15)
				)
				(justify left bottom)
				(hide yes)
			)
		)
		(pin "1"
		)
		(instances
			(project "data-center-rdimm-ddr5-tester"
				(path ""
					(reference "#PWR0310")
					(unit 1)
				)
			)
		)
	)
	(symbol
		(lib_id "antmicroResistors0402:R_0R_0402")
		(at 339.09 66.04 90)
		(unit 1)
		(exclude_from_sim no)
		(in_bom yes)
		(on_board yes)
		(dnp no)
		(fields_autoplaced yes)
		(property "Reference" "R166"
			(at 340.995 62.2299 90)
			(effects
				(font
					(size 1.27 1.27)
				)
				(justify right)
			)
		)
		(property "Value" "R_0R_0402"
			(at 351.79 45.72 0)
			(effects
				(font
					(size 1.27 1.27)
					(thickness 0.15)
				)
				(justify left bottom)
				(hide yes)
			)
		)
		(property "Footprint" "antmicro-footprints:R_0402_1005Metric"
			(at 354.33 45.72 0)
			(effects
				(font
					(size 1.27 1.27)
					(thickness 0.15)
				)
				(justify left bottom)
				(hide yes)
			)
		)
		(property "Datasheet" "https://industrial.panasonic.com/cdbs/www-data/pdf/RDA0000/AOA0000C301.pdf"
			(at 356.87 45.72 0)
			(effects
				(font
					(size 1.27 1.27)
					(thickness 0.15)
				)
				(justify left bottom)
				(hide yes)
			)
		)
		(property "Description" ""
			(at 339.09 66.04 0)
			(effects
				(font
					(size 1.27 1.27)
				)
				(hide yes)
			)
		)
		(property "Manufacturer" "Panasonic"
			(at 361.95 45.72 0)
			(effects
				(font
					(size 1.27 1.27)
					(thickness 0.15)
				)
				(justify left bottom)
				(hide yes)
			)
		)
		(property "MPN" "ERJ2GE0R00X"
			(at 359.41 45.72 0)
			(effects
				(font
					(size 1.27 1.27)
					(thickness 0.15)
				)
				(justify left bottom)
				(hide yes)
			)
		)
		(property "Val" "0R"
			(at 340.995 64.7699 90)
			(effects
				(font
					(size 1.27 1.27)
					(thickness 0.15)
				)
				(justify right)
			)
		)
		(property "License" "Apache-2.0"
			(at 364.49 45.72 0)
			(effects
				(font
					(size 1.27 1.27)
					(thickness 0.15)
				)
				(justify left bottom)
				(hide yes)
			)
		)
		(property "Author" "Antmicro"
			(at 367.03 45.72 0)
			(effects
				(font
					(size 1.27 1.27)
					(thickness 0.15)
				)
				(justify left bottom)
				(hide yes)
			)
		)
		(property "Tolerance" "~"
			(at 349.25 45.72 0)
			(effects
				(font
					(size 1.27 1.27)
				)
				(justify left bottom)
				(hide yes)
			)
		)
		(property "Current" "1A"
			(at 340.995 66.0399 90)
			(effects
				(font
					(size 1.27 1.27)
					(thickness 0.15)
				)
				(justify right)
				(hide yes)
			)
		)
		(pin "1"
		)
		(pin "2"
		)
		(instances
			(project "data-center-rdimm-ddr5-tester"
				(path ""
					(reference "R166")
					(unit 1)
				)
			)
		)
	)
	(symbol
		(lib_id "antmicroResistors0402:R_0R_0402")
		(at 175.26 217.17 0)
		(unit 1)
		(exclude_from_sim no)
		(in_bom yes)
		(on_board yes)
		(dnp no)
		(property "Reference" "R212"
			(at 182.88 215.9 0)
			(effects
				(font
					(size 1.27 1.27)
					(thickness 0.15)
				)
			)
		)
		(property "Value" "R_0R_0402"
			(at 195.58 229.87 0)
			(effects
				(font
					(size 1.27 1.27)
					(thickness 0.15)
				)
				(justify left bottom)
				(hide yes)
			)
		)
		(property "Footprint" "antmicro-footprints:R_0402_1005Metric"
			(at 195.58 232.41 0)
			(effects
				(font
					(size 1.27 1.27)
					(thickness 0.15)
				)
				(justify left bottom)
				(hide yes)
			)
		)
		(property "Datasheet" "https://industrial.panasonic.com/cdbs/www-data/pdf/RDA0000/AOA0000C301.pdf"
			(at 195.58 234.95 0)
			(effects
				(font
					(size 1.27 1.27)
					(thickness 0.15)
				)
				(justify left bottom)
				(hide yes)
			)
		)
		(property "Description" ""
			(at 175.26 217.17 0)
			(effects
				(font
					(size 1.27 1.27)
				)
				(hide yes)
			)
		)
		(property "MPN" "ERJ2GE0R00X"
			(at 195.58 237.49 0)
			(effects
				(font
					(size 1.27 1.27)
					(thickness 0.15)
				)
				(justify left bottom)
				(hide yes)
			)
		)
		(property "Manufacturer" "Panasonic"
			(at 195.58 240.03 0)
			(effects
				(font
					(size 1.27 1.27)
					(thickness 0.15)
				)
				(justify left bottom)
				(hide yes)
			)
		)
		(property "License" "Apache-2.0"
			(at 195.58 242.57 0)
			(effects
				(font
					(size 1.27 1.27)
					(thickness 0.15)
				)
				(justify left bottom)
				(hide yes)
			)
		)
		(property "Author" "Antmicro"
			(at 195.58 245.11 0)
			(effects
				(font
					(size 1.27 1.27)
					(thickness 0.15)
				)
				(justify left bottom)
				(hide yes)
			)
		)
		(property "Val" "0R"
			(at 181.61 218.44 0)
			(effects
				(font
					(size 1.27 1.27)
					(thickness 0.15)
				)
			)
		)
		(property "Tolerance" "~"
			(at 195.58 227.33 0)
			(effects
				(font
					(size 1.27 1.27)
				)
				(justify left bottom)
				(hide yes)
			)
		)
		(property "Current" "1A"
			(at 195.58 247.65 0)
			(effects
				(font
					(size 1.27 1.27)
					(thickness 0.15)
				)
				(justify left bottom)
				(hide yes)
			)
		)
		(pin "2"
		)
		(pin "1"
		)
		(instances
			(project "data-center-rdimm-ddr5-tester"
				(path ""
					(reference "R212")
					(unit 1)
				)
			)
		)
	)
	(symbol
		(lib_id "antmicropower:GND")
		(at 339.09 78.74 0)
		(unit 1)
		(exclude_from_sim no)
		(in_bom yes)
		(on_board yes)
		(dnp no)
		(fields_autoplaced yes)
		(property "Reference" "#PWR0345"
			(at 339.09 85.09 0)
			(effects
				(font
					(size 1.27 1.27)
				)
				(hide yes)
			)
		)
		(property "Value" "GND"
			(at 337.185 83.185 0)
			(effects
				(font
					(size 1.27 1.27)
					(thickness 0.15)
				)
				(justify left bottom)
			)
		)
		(property "Footprint" ""
			(at 347.98 86.36 0)
			(effects
				(font
					(size 1.27 1.27)
					(thickness 0.15)
				)
				(justify left bottom)
				(hide yes)
			)
		)
		(property "Datasheet" ""
			(at 347.98 91.44 0)
			(effects
				(font
					(size 1.27 1.27)
					(thickness 0.15)
				)
				(justify left bottom)
				(hide yes)
			)
		)
		(property "Description" ""
			(at 339.09 78.74 0)
			(effects
				(font
					(size 1.27 1.27)
				)
				(hide yes)
			)
		)
		(property "Author" "Antmicro"
			(at 347.98 83.82 0)
			(effects
				(font
					(size 1.27 1.27)
					(thickness 0.15)
				)
				(justify left bottom)
				(hide yes)
			)
		)
		(property "License" "Apache-2.0"
			(at 347.98 86.36 0)
			(effects
				(font
					(size 1.27 1.27)
					(thickness 0.15)
				)
				(justify left bottom)
				(hide yes)
			)
		)
		(pin "1"
		)
		(instances
			(project "data-center-rdimm-ddr5-tester"
				(path ""
					(reference "#PWR0345")
					(unit 1)
				)
			)
		)
	)
	(symbol
		(lib_id "antmicropower:+3V3_AON")
		(at 128.27 207.01 0)
		(unit 1)
		(exclude_from_sim no)
		(in_bom yes)
		(on_board yes)
		(dnp no)
		(property "Reference" "#PWR0317"
			(at 128.27 210.82 0)
			(effects
				(font
					(size 1.27 1.27)
				)
				(hide yes)
			)
		)
		(property "Value" "+3V3_AON"
			(at 128.27 203.2 0)
			(effects
				(font
					(size 1.27 1.27)
				)
			)
		)
		(property "Footprint" ""
			(at 128.27 207.01 0)
			(effects
				(font
					(size 1.27 1.27)
				)
				(hide yes)
			)
		)
		(property "Datasheet" ""
			(at 128.27 207.01 0)
			(effects
				(font
					(size 1.27 1.27)
				)
				(hide yes)
			)
		)
		(property "Description" ""
			(at 128.27 207.01 0)
			(effects
				(font
					(size 1.27 1.27)
				)
				(hide yes)
			)
		)
		(pin "1"
		)
		(instances
			(project "data-center-rdimm-ddr5-tester"
				(path ""
					(reference "#PWR0317")
					(unit 1)
				)
			)
		)
	)
	(symbol
		(lib_id "antmicroShuntsJumpers:Net-Tie_P0.127mm")
		(at 222.25 116.84 90)
		(unit 1)
		(exclude_from_sim no)
		(in_bom no)
		(on_board yes)
		(dnp no)
		(fields_autoplaced yes)
		(property "Reference" "NT8"
			(at 220.98 116.84 0)
			(effects
				(font
					(size 1.27 1.27)
				)
				(hide yes)
			)
		)
		(property "Value" "Net-Tie_P0.127mm"
			(at 229.87 95.25 0)
			(effects
				(font
					(size 1.27 1.27)
					(thickness 0.15)
				)
				(justify left bottom)
				(hide yes)
			)
		)
		(property "Footprint" "antmicro-footprints:NetTie-2_SMD_Pad0.127mm"
			(at 234.95 95.25 0)
			(effects
				(font
					(size 1.27 1.27)
					(thickness 0.15)
				)
				(justify left bottom)
				(hide yes)
			)
		)
		(property "Datasheet" ""
			(at 237.49 95.25 0)
			(effects
				(font
					(size 1.27 1.27)
					(thickness 0.15)
				)
				(justify left bottom)
				(hide yes)
			)
		)
		(property "Description" ""
			(at 222.25 116.84 0)
			(effects
				(font
					(size 1.27 1.27)
				)
				(hide yes)
			)
		)
		(property "MPN" ""
			(at 232.41 95.25 0)
			(effects
				(font
					(size 1.27 1.27)
					(thickness 0.15)
				)
				(justify left bottom)
			)
		)
		(property "Manufacturer" ""
			(at 240.03 95.25 0)
			(effects
				(font
					(size 1.27 1.27)
					(thickness 0.15)
				)
				(justify left bottom)
				(hide yes)
			)
		)
		(property "Author" "Antmicro"
			(at 242.57 95.25 0)
			(effects
				(font
					(size 1.27 1.27)
					(thickness 0.15)
				)
				(justify left bottom)
				(hide yes)
			)
		)
		(property "License" "Apache-2.0"
			(at 245.11 95.25 0)
			(effects
				(font
					(size 1.27 1.27)
					(thickness 0.15)
				)
				(justify left bottom)
				(hide yes)
			)
		)
		(pin "1"
		)
		(pin "2"
		)
		(instances
			(project "data-center-rdimm-ddr5-tester"
				(path ""
					(reference "NT8")
					(unit 1)
				)
			)
		)
	)
	(symbol
		(lib_id "antmicroResistorsmisc:R_0R01_1206")
		(at 223.52 91.44 0)
		(unit 1)
		(exclude_from_sim no)
		(in_bom yes)
		(on_board yes)
		(dnp no)
		(property "Reference" "R147"
			(at 226.06 86.36 0)
			(effects
				(font
					(size 1.27 1.27)
				)
			)
		)
		(property "Value" "R_0R01_1206"
			(at 243.84 104.14 0)
			(effects
				(font
					(size 1.27 1.27)
					(thickness 0.15)
				)
				(justify left bottom)
				(hide yes)
			)
		)
		(property "Footprint" "antmicro-footprints:R_1206_3216Metric"
			(at 243.84 106.68 0)
			(effects
				(font
					(size 1.27 1.27)
					(thickness 0.15)
				)
				(justify left bottom)
				(hide yes)
			)
		)
		(property "Datasheet" "https://www.yageo.com/upload/media/product/productsearch/datasheet/rchip/PYu-RL_Group_521_RoHS_L_2.pdf"
			(at 243.84 109.22 0)
			(effects
				(font
					(size 1.27 1.27)
					(thickness 0.15)
				)
				(justify left bottom)
				(hide yes)
			)
		)
		(property "Description" ""
			(at 223.52 91.44 0)
			(effects
				(font
					(size 1.27 1.27)
				)
				(hide yes)
			)
		)
		(property "Manufacturer" "YAGEO"
			(at 243.84 114.3 0)
			(effects
				(font
					(size 1.27 1.27)
					(thickness 0.15)
				)
				(justify left bottom)
				(hide yes)
			)
		)
		(property "MPN" "RL1206FR-7W0R01L"
			(at 243.84 111.76 0)
			(effects
				(font
					(size 1.27 1.27)
					(thickness 0.15)
				)
				(justify left bottom)
				(hide yes)
			)
		)
		(property "Val" "0R01"
			(at 226.06 88.9 0)
			(effects
				(font
					(size 1.27 1.27)
					(thickness 0.15)
				)
			)
		)
		(property "License" "Apache-2.0"
			(at 243.84 116.84 0)
			(effects
				(font
					(size 1.27 1.27)
					(thickness 0.15)
				)
				(justify left bottom)
				(hide yes)
			)
		)
		(property "Author" "Antmicro"
			(at 243.84 119.38 0)
			(effects
				(font
					(size 1.27 1.27)
					(thickness 0.15)
				)
				(justify left bottom)
				(hide yes)
			)
		)
		(property "Tolerance" "1%"
			(at 243.84 101.6 0)
			(effects
				(font
					(size 1.27 1.27)
				)
				(justify left bottom)
				(hide yes)
			)
		)
		(pin "1"
		)
		(pin "2"
		)
		(instances
			(project "data-center-rdimm-ddr5-tester"
				(path ""
					(reference "R147")
					(unit 1)
				)
			)
		)
	)
	(symbol
		(lib_id "antmicroPMICVoltageRegulatorsDCDCSwitchingRegulators:MPM54304GMN")
		(at 149.86 68.58 0)
		(unit 1)
		(exclude_from_sim no)
		(in_bom yes)
		(on_board yes)
		(dnp no)
		(fields_autoplaced yes)
		(property "Reference" "U20"
			(at 163.83 59.69 0)
			(effects
				(font
					(size 1.27 1.27)
					(thickness 0.15)
				)
			)
		)
		(property "Value" "MPM54304GMN"
			(at 196.85 73.66 0)
			(effects
				(font
					(size 1.27 1.27)
					(thickness 0.15)
				)
				(justify left bottom)
				(hide yes)
			)
		)
		(property "Footprint" "antmicro-footprints:LGA-33_7x7mm_P0.65mm"
			(at 196.85 76.2 0)
			(effects
				(font
					(size 1.27 1.27)
					(thickness 0.15)
				)
				(justify left bottom)
				(hide yes)
			)
		)
		(property "Datasheet" "https://www.monolithicpower.com/en/documentview/productdocument/index/version/2/document_type/Datasheet/lang/en/sku/MPM54304/document_id/4982/"
			(at 196.85 78.74 0)
			(effects
				(font
					(size 1.27 1.27)
					(thickness 0.15)
				)
				(justify left bottom)
				(hide yes)
			)
		)
		(property "Description" ""
			(at 149.86 68.58 0)
			(effects
				(font
					(size 1.27 1.27)
				)
				(hide yes)
			)
		)
		(property "MPN" "MPM54304GMN-0000"
			(at 163.83 62.23 0)
			(effects
				(font
					(size 1.27 1.27)
					(thickness 0.15)
				)
			)
		)
		(property "Manufacturer" "Monolithic Power Systems"
			(at 196.85 83.82 0)
			(effects
				(font
					(size 1.27 1.27)
					(thickness 0.15)
				)
				(justify left bottom)
				(hide yes)
			)
		)
		(property "Author" "Antmicro"
			(at 196.85 86.36 0)
			(effects
				(font
					(size 1.27 1.27)
					(thickness 0.15)
				)
				(justify left bottom)
				(hide yes)
			)
		)
		(property "License" "Apache-2.0"
			(at 196.85 88.9 0)
			(effects
				(font
					(size 1.27 1.27)
					(thickness 0.15)
				)
				(justify left bottom)
				(hide yes)
			)
		)
		(pin "8"
		)
		(pin "30"
		)
		(pin "3"
		)
		(pin "29"
		)
		(pin "24"
		)
		(pin "7"
		)
		(pin "25"
		)
		(pin "17"
		)
		(pin "16"
		)
		(pin "33"
		)
		(pin "27"
		)
		(pin "5"
		)
		(pin "19"
		)
		(pin "6"
		)
		(pin "13"
		)
		(pin "28"
		)
		(pin "22"
		)
		(pin "2"
		)
		(pin "18"
		)
		(pin "20"
		)
		(pin "21"
		)
		(pin "14"
		)
		(pin "4"
		)
		(pin "23"
		)
		(pin "10"
		)
		(pin "11"
		)
		(pin "26"
		)
		(pin "15"
		)
		(pin "32"
		)
		(pin "12"
		)
		(pin "31"
		)
		(pin "1"
		)
		(pin "9"
		)
		(instances
			(project "data-center-rdimm-ddr5-tester"
				(path ""
					(reference "U20")
					(unit 1)
				)
			)
		)
	)
	(symbol
		(lib_id "antmicropower:VDD")
		(at 250.19 90.17 0)
		(unit 1)
		(exclude_from_sim no)
		(in_bom yes)
		(on_board yes)
		(dnp no)
		(fields_autoplaced yes)
		(property "Reference" "#PWR048"
			(at 250.19 93.98 0)
			(effects
				(font
					(size 1.27 1.27)
				)
				(hide yes)
			)
		)
		(property "Value" "VDDQ"
			(at 250.19 85.09 0)
			(effects
				(font
					(size 1.27 1.27)
				)
			)
		)
		(property "Footprint" ""
			(at 250.19 90.17 0)
			(effects
				(font
					(size 1.27 1.27)
				)
				(hide yes)
			)
		)
		(property "Datasheet" ""
			(at 250.19 90.17 0)
			(effects
				(font
					(size 1.27 1.27)
				)
				(hide yes)
			)
		)
		(property "Description" ""
			(at 250.19 90.17 0)
			(effects
				(font
					(size 1.27 1.27)
				)
				(hide yes)
			)
		)
		(pin "1"
		)
		(instances
			(project "data-center-rdimm-ddr5-tester"
				(path ""
					(reference "#PWR048")
					(unit 1)
				)
			)
		)
	)
	(symbol
		(lib_id "antmicroResistors0402:R_0R_0402")
		(at 339.09 111.76 90)
		(unit 1)
		(exclude_from_sim no)
		(in_bom no)
		(on_board yes)
		(dnp yes)
		(property "Reference" "R169"
			(at 340.995 107.95 90)
			(effects
				(font
					(size 1.27 1.27)
				)
				(justify right)
			)
		)
		(property "Value" "R_0R_0402"
			(at 351.79 91.44 0)
			(effects
				(font
					(size 1.27 1.27)
					(thickness 0.15)
				)
				(justify left bottom)
				(hide yes)
			)
		)
		(property "Footprint" "antmicro-footprints:R_0402_1005Metric"
			(at 354.33 91.44 0)
			(effects
				(font
					(size 1.27 1.27)
					(thickness 0.15)
				)
				(justify left bottom)
				(hide yes)
			)
		)
		(property "Datasheet" "https://industrial.panasonic.com/cdbs/www-data/pdf/RDA0000/AOA0000C301.pdf"
			(at 356.87 91.44 0)
			(effects
				(font
					(size 1.27 1.27)
					(thickness 0.15)
				)
				(justify left bottom)
				(hide yes)
			)
		)
		(property "Description" ""
			(at 339.09 111.76 0)
			(effects
				(font
					(size 1.27 1.27)
				)
				(hide yes)
			)
		)
		(property "Manufacturer" "Panasonic"
			(at 361.95 91.44 0)
			(effects
				(font
					(size 1.27 1.27)
					(thickness 0.15)
				)
				(justify left bottom)
				(hide yes)
			)
		)
		(property "MPN" "ERJ2GE0R00X"
			(at 359.41 91.44 0)
			(effects
				(font
					(size 1.27 1.27)
					(thickness 0.15)
				)
				(justify left bottom)
				(hide yes)
			)
		)
		(property "Val" "0R"
			(at 340.995 110.49 90)
			(effects
				(font
					(size 1.27 1.27)
					(thickness 0.15)
				)
				(justify right)
			)
		)
		(property "License" "Apache-2.0"
			(at 364.49 91.44 0)
			(effects
				(font
					(size 1.27 1.27)
					(thickness 0.15)
				)
				(justify left bottom)
				(hide yes)
			)
		)
		(property "Author" "Antmicro"
			(at 367.03 91.44 0)
			(effects
				(font
					(size 1.27 1.27)
					(thickness 0.15)
				)
				(justify left bottom)
				(hide yes)
			)
		)
		(property "Tolerance" "~"
			(at 349.25 91.44 0)
			(effects
				(font
					(size 1.27 1.27)
				)
				(justify left bottom)
				(hide yes)
			)
		)
		(property "Current" "1A"
			(at 340.995 113.0299 90)
			(effects
				(font
					(size 1.27 1.27)
					(thickness 0.15)
				)
				(justify right)
				(hide yes)
			)
		)
		(pin "1"
		)
		(pin "2"
		)
		(instances
			(project "data-center-rdimm-ddr5-tester"
				(path ""
					(reference "R169")
					(unit 1)
				)
			)
		)
	)
	(symbol
		(lib_id "antmicropower:GND")
		(at 147.32 236.22 0)
		(unit 1)
		(exclude_from_sim no)
		(in_bom yes)
		(on_board yes)
		(dnp no)
		(fields_autoplaced yes)
		(property "Reference" "#PWR0386"
			(at 147.32 242.57 0)
			(effects
				(font
					(size 1.27 1.27)
				)
				(hide yes)
			)
		)
		(property "Value" "GND"
			(at 145.415 240.665 0)
			(effects
				(font
					(size 1.27 1.27)
					(thickness 0.15)
				)
				(justify left bottom)
			)
		)
		(property "Footprint" ""
			(at 156.21 243.84 0)
			(effects
				(font
					(size 1.27 1.27)
					(thickness 0.15)
				)
				(justify left bottom)
				(hide yes)
			)
		)
		(property "Datasheet" ""
			(at 156.21 248.92 0)
			(effects
				(font
					(size 1.27 1.27)
					(thickness 0.15)
				)
				(justify left bottom)
				(hide yes)
			)
		)
		(property "Description" ""
			(at 147.32 236.22 0)
			(effects
				(font
					(size 1.27 1.27)
				)
				(hide yes)
			)
		)
		(property "Author" "Antmicro"
			(at 156.21 241.3 0)
			(effects
				(font
					(size 1.27 1.27)
					(thickness 0.15)
				)
				(justify left bottom)
				(hide yes)
			)
		)
		(property "License" "Apache-2.0"
			(at 156.21 243.84 0)
			(effects
				(font
					(size 1.27 1.27)
					(thickness 0.15)
				)
				(justify left bottom)
				(hide yes)
			)
		)
		(pin "1"
		)
		(instances
			(project "data-center-rdimm-ddr5-tester"
				(path ""
					(reference "#PWR0386")
					(unit 1)
				)
			)
		)
	)
	(symbol
		(lib_id "antmicroResistors0402:R_0R_0402")
		(at 175.26 229.87 0)
		(unit 1)
		(exclude_from_sim no)
		(in_bom yes)
		(on_board yes)
		(dnp no)
		(property "Reference" "R214"
			(at 182.88 228.6 0)
			(effects
				(font
					(size 1.27 1.27)
					(thickness 0.15)
				)
			)
		)
		(property "Value" "R_0R_0402"
			(at 195.58 242.57 0)
			(effects
				(font
					(size 1.27 1.27)
					(thickness 0.15)
				)
				(justify left bottom)
				(hide yes)
			)
		)
		(property "Footprint" "antmicro-footprints:R_0402_1005Metric"
			(at 195.58 245.11 0)
			(effects
				(font
					(size 1.27 1.27)
					(thickness 0.15)
				)
				(justify left bottom)
				(hide yes)
			)
		)
		(property "Datasheet" "https://industrial.panasonic.com/cdbs/www-data/pdf/RDA0000/AOA0000C301.pdf"
			(at 195.58 247.65 0)
			(effects
				(font
					(size 1.27 1.27)
					(thickness 0.15)
				)
				(justify left bottom)
				(hide yes)
			)
		)
		(property "Description" ""
			(at 175.26 229.87 0)
			(effects
				(font
					(size 1.27 1.27)
				)
				(hide yes)
			)
		)
		(property "MPN" "ERJ2GE0R00X"
			(at 195.58 250.19 0)
			(effects
				(font
					(size 1.27 1.27)
					(thickness 0.15)
				)
				(justify left bottom)
				(hide yes)
			)
		)
		(property "Manufacturer" "Panasonic"
			(at 195.58 252.73 0)
			(effects
				(font
					(size 1.27 1.27)
					(thickness 0.15)
				)
				(justify left bottom)
				(hide yes)
			)
		)
		(property "License" "Apache-2.0"
			(at 195.58 255.27 0)
			(effects
				(font
					(size 1.27 1.27)
					(thickness 0.15)
				)
				(justify left bottom)
				(hide yes)
			)
		)
		(property "Author" "Antmicro"
			(at 195.58 257.81 0)
			(effects
				(font
					(size 1.27 1.27)
					(thickness 0.15)
				)
				(justify left bottom)
				(hide yes)
			)
		)
		(property "Val" "0R"
			(at 181.61 231.14 0)
			(effects
				(font
					(size 1.27 1.27)
					(thickness 0.15)
				)
			)
		)
		(property "Tolerance" "~"
			(at 195.58 240.03 0)
			(effects
				(font
					(size 1.27 1.27)
				)
				(justify left bottom)
				(hide yes)
			)
		)
		(property "Current" "1A"
			(at 195.58 260.35 0)
			(effects
				(font
					(size 1.27 1.27)
					(thickness 0.15)
				)
				(justify left bottom)
				(hide yes)
			)
		)
		(pin "2"
		)
		(pin "1"
		)
		(instances
			(project "data-center-rdimm-ddr5-tester"
				(path ""
					(reference "R214")
					(unit 1)
				)
			)
		)
	)
	(symbol
		(lib_id "antmicropower:GND")
		(at 339.09 114.3 0)
		(unit 1)
		(exclude_from_sim no)
		(in_bom yes)
		(on_board yes)
		(dnp no)
		(fields_autoplaced yes)
		(property "Reference" "#PWR0346"
			(at 339.09 120.65 0)
			(effects
				(font
					(size 1.27 1.27)
				)
				(hide yes)
			)
		)
		(property "Value" "GND"
			(at 337.185 118.745 0)
			(effects
				(font
					(size 1.27 1.27)
					(thickness 0.15)
				)
				(justify left bottom)
			)
		)
		(property "Footprint" ""
			(at 347.98 121.92 0)
			(effects
				(font
					(size 1.27 1.27)
					(thickness 0.15)
				)
				(justify left bottom)
				(hide yes)
			)
		)
		(property "Datasheet" ""
			(at 347.98 127 0)
			(effects
				(font
					(size 1.27 1.27)
					(thickness 0.15)
				)
				(justify left bottom)
				(hide yes)
			)
		)
		(property "Description" ""
			(at 339.09 114.3 0)
			(effects
				(font
					(size 1.27 1.27)
				)
				(hide yes)
			)
		)
		(property "Author" "Antmicro"
			(at 347.98 119.38 0)
			(effects
				(font
					(size 1.27 1.27)
					(thickness 0.15)
				)
				(justify left bottom)
				(hide yes)
			)
		)
		(property "License" "Apache-2.0"
			(at 347.98 121.92 0)
			(effects
				(font
					(size 1.27 1.27)
					(thickness 0.15)
				)
				(justify left bottom)
				(hide yes)
			)
		)
		(pin "1"
		)
		(instances
			(project "data-center-rdimm-ddr5-tester"
				(path ""
					(reference "#PWR0346")
					(unit 1)
				)
			)
		)
	)
	(symbol
		(lib_id "antmicroTestPoints:TP_1mm_SMD")
		(at 252.73 73.66 0)
		(unit 1)
		(exclude_from_sim no)
		(in_bom no)
		(on_board yes)
		(dnp no)
		(fields_autoplaced yes)
		(property "Reference" "TP13"
			(at 257.302 74.0938 0)
			(effects
				(font
					(size 1.27 1.27)
				)
				(justify left)
			)
		)
		(property "Value" "TP_1mm_SMD"
			(at 267.97 81.28 0)
			(effects
				(font
					(size 1.27 1.27)
					(thickness 0.15)
				)
				(justify left bottom)
				(hide yes)
			)
		)
		(property "Footprint" "antmicro-footprints:TP_SMD_1mm"
			(at 267.97 83.82 0)
			(effects
				(font
					(size 1.27 1.27)
					(thickness 0.15)
				)
				(justify left bottom)
				(hide yes)
			)
		)
		(property "Datasheet" ""
			(at 267.97 86.36 0)
			(effects
				(font
					(size 1.27 1.27)
					(thickness 0.15)
				)
				(justify left bottom)
				(hide yes)
			)
		)
		(property "Description" ""
			(at 252.73 73.66 0)
			(effects
				(font
					(size 1.27 1.27)
				)
				(hide yes)
			)
		)
		(property "MPN" ""
			(at 252.73 73.66 0)
			(effects
				(font
					(size 1.27 1.27)
				)
				(hide yes)
			)
		)
		(property "Manufacturer" ""
			(at 252.73 73.66 0)
			(effects
				(font
					(size 1.27 1.27)
				)
				(hide yes)
			)
		)
		(property "Author" "Antmicro"
			(at 267.97 88.9 0)
			(effects
				(font
					(size 1.27 1.27)
					(thickness 0.15)
				)
				(justify left bottom)
				(hide yes)
			)
		)
		(property "License" "Apache-2.0"
			(at 267.97 91.44 0)
			(effects
				(font
					(size 1.27 1.27)
					(thickness 0.15)
				)
				(justify left bottom)
				(hide yes)
			)
		)
		(pin "1"
		)
		(instances
			(project "data-center-rdimm-ddr5-tester"
				(path ""
					(reference "TP13")
					(unit 1)
				)
			)
		)
	)
	(symbol
		(lib_id "antmicroCapacitors0603:C_22u_0603")
		(at 203.2 99.06 90)
		(unit 1)
		(exclude_from_sim no)
		(in_bom yes)
		(on_board yes)
		(dnp no)
		(property "Reference" "C192"
			(at 203.835 94.615 90)
			(effects
				(font
					(size 1.27 1.27)
				)
				(justify right)
			)
		)
		(property "Value" "C_22u_0603"
			(at 213.36 78.74 0)
			(effects
				(font
					(size 1.27 1.27)
					(thickness 0.15)
				)
				(justify left bottom)
				(hide yes)
			)
		)
		(property "Footprint" "antmicro-footprints:C_0603_1608Metric"
			(at 215.9 78.74 0)
			(effects
				(font
					(size 1.27 1.27)
					(thickness 0.15)
				)
				(justify left bottom)
				(hide yes)
			)
		)
		(property "Datasheet" "https://www.murata.com/products/productdetail?partno=GRM188R60J226MEA0%23"
			(at 218.44 78.74 0)
			(effects
				(font
					(size 1.27 1.27)
					(thickness 0.15)
				)
				(justify left bottom)
				(hide yes)
			)
		)
		(property "Description" ""
			(at 203.2 99.06 0)
			(effects
				(font
					(size 1.27 1.27)
				)
				(hide yes)
			)
		)
		(property "Manufacturer" "Murata"
			(at 223.52 78.74 0)
			(effects
				(font
					(size 1.27 1.27)
					(thickness 0.15)
				)
				(justify left bottom)
				(hide yes)
			)
		)
		(property "MPN" "GRM188R60J226MEA0D"
			(at 220.98 78.74 0)
			(effects
				(font
					(size 1.27 1.27)
					(thickness 0.15)
				)
				(justify left bottom)
				(hide yes)
			)
		)
		(property "Val" "22u"
			(at 203.835 98.425 90)
			(effects
				(font
					(size 1.27 1.27)
					(thickness 0.15)
				)
				(justify right)
			)
		)
		(property "License" "Apache-2.0"
			(at 226.06 78.74 0)
			(effects
				(font
					(size 1.27 1.27)
					(thickness 0.15)
				)
				(justify left bottom)
				(hide yes)
			)
		)
		(property "Author" "Antmicro"
			(at 228.6 78.74 0)
			(effects
				(font
					(size 1.27 1.27)
					(thickness 0.15)
				)
				(justify left bottom)
				(hide yes)
			)
		)
		(property "Voltage" ""
			(at 231.14 78.74 0)
			(effects
				(font
					(size 1.27 1.27)
				)
				(justify left bottom)
				(hide yes)
			)
		)
		(property "Dielectric" ""
			(at 233.68 78.74 0)
			(effects
				(font
					(size 1.27 1.27)
				)
				(justify left bottom)
				(hide yes)
			)
		)
		(pin "1"
		)
		(pin "2"
		)
		(instances
			(project "data-center-rdimm-ddr5-tester"
				(path ""
					(reference "C192")
					(unit 1)
				)
			)
		)
	)
	(symbol
		(lib_id "antmicroResistorsmisc:R_0R01_1206")
		(at 223.52 73.66 0)
		(unit 1)
		(exclude_from_sim no)
		(in_bom yes)
		(on_board yes)
		(dnp no)
		(property "Reference" "R146"
			(at 226.06 68.58 0)
			(effects
				(font
					(size 1.27 1.27)
				)
			)
		)
		(property "Value" "R_0R01_1206"
			(at 243.84 86.36 0)
			(effects
				(font
					(size 1.27 1.27)
					(thickness 0.15)
				)
				(justify left bottom)
				(hide yes)
			)
		)
		(property "Footprint" "antmicro-footprints:R_1206_3216Metric"
			(at 243.84 88.9 0)
			(effects
				(font
					(size 1.27 1.27)
					(thickness 0.15)
				)
				(justify left bottom)
				(hide yes)
			)
		)
		(property "Datasheet" "https://www.yageo.com/upload/media/product/productsearch/datasheet/rchip/PYu-RL_Group_521_RoHS_L_2.pdf"
			(at 243.84 91.44 0)
			(effects
				(font
					(size 1.27 1.27)
					(thickness 0.15)
				)
				(justify left bottom)
				(hide yes)
			)
		)
		(property "Description" ""
			(at 223.52 73.66 0)
			(effects
				(font
					(size 1.27 1.27)
				)
				(hide yes)
			)
		)
		(property "Manufacturer" "YAGEO"
			(at 243.84 96.52 0)
			(effects
				(font
					(size 1.27 1.27)
					(thickness 0.15)
				)
				(justify left bottom)
				(hide yes)
			)
		)
		(property "MPN" "RL1206FR-7W0R01L"
			(at 243.84 93.98 0)
			(effects
				(font
					(size 1.27 1.27)
					(thickness 0.15)
				)
				(justify left bottom)
				(hide yes)
			)
		)
		(property "Val" "0R01"
			(at 226.06 71.12 0)
			(effects
				(font
					(size 1.27 1.27)
					(thickness 0.15)
				)
			)
		)
		(property "License" "Apache-2.0"
			(at 243.84 99.06 0)
			(effects
				(font
					(size 1.27 1.27)
					(thickness 0.15)
				)
				(justify left bottom)
				(hide yes)
			)
		)
		(property "Author" "Antmicro"
			(at 243.84 101.6 0)
			(effects
				(font
					(size 1.27 1.27)
					(thickness 0.15)
				)
				(justify left bottom)
				(hide yes)
			)
		)
		(property "Tolerance" "1%"
			(at 243.84 83.82 0)
			(effects
				(font
					(size 1.27 1.27)
				)
				(justify left bottom)
				(hide yes)
			)
		)
		(pin "1"
		)
		(pin "2"
		)
		(instances
			(project "data-center-rdimm-ddr5-tester"
				(path ""
					(reference "R146")
					(unit 1)
				)
			)
		)
	)
	(symbol
		(lib_id "antmicroCapacitors0603:C_22u_0603")
		(at 194.31 81.28 90)
		(unit 1)
		(exclude_from_sim no)
		(in_bom yes)
		(on_board yes)
		(dnp no)
		(property "Reference" "C185"
			(at 194.945 76.835 90)
			(effects
				(font
					(size 1.27 1.27)
				)
				(justify right)
			)
		)
		(property "Value" "C_22u_0603"
			(at 204.47 60.96 0)
			(effects
				(font
					(size 1.27 1.27)
					(thickness 0.15)
				)
				(justify left bottom)
				(hide yes)
			)
		)
		(property "Footprint" "antmicro-footprints:C_0603_1608Metric"
			(at 207.01 60.96 0)
			(effects
				(font
					(size 1.27 1.27)
					(thickness 0.15)
				)
				(justify left bottom)
				(hide yes)
			)
		)
		(property "Datasheet" "https://www.murata.com/products/productdetail?partno=GRM188R60J226MEA0%23"
			(at 209.55 60.96 0)
			(effects
				(font
					(size 1.27 1.27)
					(thickness 0.15)
				)
				(justify left bottom)
				(hide yes)
			)
		)
		(property "Description" ""
			(at 194.31 81.28 0)
			(effects
				(font
					(size 1.27 1.27)
				)
				(hide yes)
			)
		)
		(property "Manufacturer" "Murata"
			(at 214.63 60.96 0)
			(effects
				(font
					(size 1.27 1.27)
					(thickness 0.15)
				)
				(justify left bottom)
				(hide yes)
			)
		)
		(property "MPN" "GRM188R60J226MEA0D"
			(at 212.09 60.96 0)
			(effects
				(font
					(size 1.27 1.27)
					(thickness 0.15)
				)
				(justify left bottom)
				(hide yes)
			)
		)
		(property "Val" "22u"
			(at 194.945 80.645 90)
			(effects
				(font
					(size 1.27 1.27)
					(thickness 0.15)
				)
				(justify right)
			)
		)
		(property "License" "Apache-2.0"
			(at 217.17 60.96 0)
			(effects
				(font
					(size 1.27 1.27)
					(thickness 0.15)
				)
				(justify left bottom)
				(hide yes)
			)
		)
		(property "Author" "Antmicro"
			(at 219.71 60.96 0)
			(effects
				(font
					(size 1.27 1.27)
					(thickness 0.15)
				)
				(justify left bottom)
				(hide yes)
			)
		)
		(property "Voltage" ""
			(at 222.25 60.96 0)
			(effects
				(font
					(size 1.27 1.27)
				)
				(justify left bottom)
				(hide yes)
			)
		)
		(property "Dielectric" ""
			(at 224.79 60.96 0)
			(effects
				(font
					(size 1.27 1.27)
				)
				(justify left bottom)
				(hide yes)
			)
		)
		(pin "1"
		)
		(pin "2"
		)
		(instances
			(project "data-center-rdimm-ddr5-tester"
				(path ""
					(reference "C185")
					(unit 1)
				)
			)
		)
	)
	(symbol
		(lib_id "antmicropower:PWR_FLAG")
		(at 241.3 90.17 0)
		(unit 1)
		(exclude_from_sim no)
		(in_bom yes)
		(on_board yes)
		(dnp no)
		(fields_autoplaced yes)
		(property "Reference" "#FLG014"
			(at 241.3 88.265 0)
			(effects
				(font
					(size 1.27 1.27)
				)
				(hide yes)
			)
		)
		(property "Value" "PWR_FLAG"
			(at 241.3 86.5942 0)
			(effects
				(font
					(size 1.27 1.27)
				)
			)
		)
		(property "Footprint" ""
			(at 241.3 90.17 0)
			(effects
				(font
					(size 1.27 1.27)
				)
				(hide yes)
			)
		)
		(property "Datasheet" ""
			(at 241.3 90.17 0)
			(effects
				(font
					(size 1.27 1.27)
				)
				(hide yes)
			)
		)
		(property "Description" ""
			(at 241.3 90.17 0)
			(effects
				(font
					(size 1.27 1.27)
				)
				(hide yes)
			)
		)
		(pin "1"
		)
		(instances
			(project "data-center-rdimm-ddr5-tester"
				(path ""
					(reference "#FLG014")
					(unit 1)
				)
			)
		)
	)
	(symbol
		(lib_id "antmicroCapacitors0603:C_22u_0603")
		(at 194.31 59.69 90)
		(unit 1)
		(exclude_from_sim no)
		(in_bom yes)
		(on_board yes)
		(dnp no)
		(property "Reference" "C184"
			(at 194.945 55.245 90)
			(effects
				(font
					(size 1.27 1.27)
				)
				(justify right)
			)
		)
		(property "Value" "C_22u_0603"
			(at 204.47 39.37 0)
			(effects
				(font
					(size 1.27 1.27)
					(thickness 0.15)
				)
				(justify left bottom)
				(hide yes)
			)
		)
		(property "Footprint" "antmicro-footprints:C_0603_1608Metric"
			(at 207.01 39.37 0)
			(effects
				(font
					(size 1.27 1.27)
					(thickness 0.15)
				)
				(justify left bottom)
				(hide yes)
			)
		)
		(property "Datasheet" "https://www.murata.com/products/productdetail?partno=GRM188R60J226MEA0%23"
			(at 209.55 39.37 0)
			(effects
				(font
					(size 1.27 1.27)
					(thickness 0.15)
				)
				(justify left bottom)
				(hide yes)
			)
		)
		(property "Description" ""
			(at 194.31 59.69 0)
			(effects
				(font
					(size 1.27 1.27)
				)
				(hide yes)
			)
		)
		(property "Manufacturer" "Murata"
			(at 214.63 39.37 0)
			(effects
				(font
					(size 1.27 1.27)
					(thickness 0.15)
				)
				(justify left bottom)
				(hide yes)
			)
		)
		(property "MPN" "GRM188R60J226MEA0D"
			(at 212.09 39.37 0)
			(effects
				(font
					(size 1.27 1.27)
					(thickness 0.15)
				)
				(justify left bottom)
				(hide yes)
			)
		)
		(property "Val" "22u"
			(at 194.945 59.055 90)
			(effects
				(font
					(size 1.27 1.27)
					(thickness 0.15)
				)
				(justify right)
			)
		)
		(property "License" "Apache-2.0"
			(at 217.17 39.37 0)
			(effects
				(font
					(size 1.27 1.27)
					(thickness 0.15)
				)
				(justify left bottom)
				(hide yes)
			)
		)
		(property "Author" "Antmicro"
			(at 219.71 39.37 0)
			(effects
				(font
					(size 1.27 1.27)
					(thickness 0.15)
				)
				(justify left bottom)
				(hide yes)
			)
		)
		(property "Voltage" ""
			(at 222.25 39.37 0)
			(effects
				(font
					(size 1.27 1.27)
				)
				(justify left bottom)
				(hide yes)
			)
		)
		(property "Dielectric" ""
			(at 224.79 39.37 0)
			(effects
				(font
					(size 1.27 1.27)
				)
				(justify left bottom)
				(hide yes)
			)
		)
		(pin "1"
		)
		(pin "2"
		)
		(instances
			(project "data-center-rdimm-ddr5-tester"
				(path ""
					(reference "C184")
					(unit 1)
				)
			)
		)
	)
	(symbol
		(lib_id "antmicropower:GND")
		(at 203.2 118.11 0)
		(unit 1)
		(exclude_from_sim no)
		(in_bom yes)
		(on_board yes)
		(dnp no)
		(fields_autoplaced yes)
		(property "Reference" "#PWR0311"
			(at 203.2 124.46 0)
			(effects
				(font
					(size 1.27 1.27)
				)
				(hide yes)
			)
		)
		(property "Value" "GND"
			(at 201.295 122.555 0)
			(effects
				(font
					(size 1.27 1.27)
					(thickness 0.15)
				)
				(justify left bottom)
			)
		)
		(property "Footprint" ""
			(at 212.09 125.73 0)
			(effects
				(font
					(size 1.27 1.27)
					(thickness 0.15)
				)
				(justify left bottom)
				(hide yes)
			)
		)
		(property "Datasheet" ""
			(at 212.09 130.81 0)
			(effects
				(font
					(size 1.27 1.27)
					(thickness 0.15)
				)
				(justify left bottom)
				(hide yes)
			)
		)
		(property "Description" ""
			(at 203.2 118.11 0)
			(effects
				(font
					(size 1.27 1.27)
				)
				(hide yes)
			)
		)
		(property "Author" "Antmicro"
			(at 212.09 123.19 0)
			(effects
				(font
					(size 1.27 1.27)
					(thickness 0.15)
				)
				(justify left bottom)
				(hide yes)
			)
		)
		(property "License" "Apache-2.0"
			(at 212.09 125.73 0)
			(effects
				(font
					(size 1.27 1.27)
					(thickness 0.15)
				)
				(justify left bottom)
				(hide yes)
			)
		)
		(pin "1"
		)
		(instances
			(project "data-center-rdimm-ddr5-tester"
				(path ""
					(reference "#PWR0311")
					(unit 1)
				)
			)
		)
	)
	(symbol
		(lib_id "antmicroResistors0402:R_47k_0402")
		(at 128.27 218.44 270)
		(mirror x)
		(unit 1)
		(exclude_from_sim no)
		(in_bom yes)
		(on_board yes)
		(dnp no)
		(fields_autoplaced yes)
		(property "Reference" "R173"
			(at 130.81 214.63 90)
			(effects
				(font
					(size 1.27 1.27)
				)
				(justify left)
			)
		)
		(property "Value" "R_47k_0402"
			(at 115.57 198.12 0)
			(effects
				(font
					(size 1.27 1.27)
					(thickness 0.15)
				)
				(justify left bottom)
				(hide yes)
			)
		)
		(property "Footprint" "antmicro-footprints:R_0402_1005Metric"
			(at 113.03 198.12 0)
			(effects
				(font
					(size 1.27 1.27)
					(thickness 0.15)
				)
				(justify left bottom)
				(hide yes)
			)
		)
		(property "Datasheet" "https://www.bourns.com/docs/product-datasheets/cr.pdf"
			(at 110.49 198.12 0)
			(effects
				(font
					(size 1.27 1.27)
					(thickness 0.15)
				)
				(justify left bottom)
				(hide yes)
			)
		)
		(property "Description" ""
			(at 128.27 218.44 0)
			(effects
				(font
					(size 1.27 1.27)
				)
				(hide yes)
			)
		)
		(property "Manufacturer" "Bourns"
			(at 105.41 198.12 0)
			(effects
				(font
					(size 1.27 1.27)
					(thickness 0.15)
				)
				(justify left bottom)
				(hide yes)
			)
		)
		(property "MPN" "CR0402-FX-4702GLF"
			(at 107.95 198.12 0)
			(effects
				(font
					(size 1.27 1.27)
					(thickness 0.15)
				)
				(justify left bottom)
				(hide yes)
			)
		)
		(property "Val" "47k"
			(at 130.81 217.17 90)
			(effects
				(font
					(size 1.27 1.27)
					(thickness 0.15)
				)
				(justify left)
			)
		)
		(property "License" "Apache-2.0"
			(at 102.87 198.12 0)
			(effects
				(font
					(size 1.27 1.27)
					(thickness 0.15)
				)
				(justify left bottom)
				(hide yes)
			)
		)
		(property "Author" "Antmicro"
			(at 100.33 198.12 0)
			(effects
				(font
					(size 1.27 1.27)
					(thickness 0.15)
				)
				(justify left bottom)
				(hide yes)
			)
		)
		(property "Tolerance" "1%"
			(at 118.11 198.12 0)
			(effects
				(font
					(size 1.27 1.27)
				)
				(justify left bottom)
				(hide yes)
			)
		)
		(pin "1"
		)
		(pin "2"
		)
		(instances
			(project "data-center-rdimm-ddr5-tester"
				(path ""
					(reference "R173")
					(unit 1)
				)
			)
		)
	)
	(symbol
		(lib_id "antmicroResistors0402:R_0R_0402")
		(at 308.61 66.04 90)
		(unit 1)
		(exclude_from_sim no)
		(in_bom yes)
		(on_board yes)
		(dnp no)
		(fields_autoplaced yes)
		(property "Reference" "R155"
			(at 311.15 62.2299 90)
			(effects
				(font
					(size 1.27 1.27)
				)
				(justify right)
			)
		)
		(property "Value" "R_0R_0402"
			(at 321.31 45.72 0)
			(effects
				(font
					(size 1.27 1.27)
					(thickness 0.15)
				)
				(justify left bottom)
				(hide yes)
			)
		)
		(property "Footprint" "antmicro-footprints:R_0402_1005Metric"
			(at 323.85 45.72 0)
			(effects
				(font
					(size 1.27 1.27)
					(thickness 0.15)
				)
				(justify left bottom)
				(hide yes)
			)
		)
		(property "Datasheet" "https://industrial.panasonic.com/cdbs/www-data/pdf/RDA0000/AOA0000C301.pdf"
			(at 326.39 45.72 0)
			(effects
				(font
					(size 1.27 1.27)
					(thickness 0.15)
				)
				(justify left bottom)
				(hide yes)
			)
		)
		(property "Description" ""
			(at 308.61 66.04 0)
			(effects
				(font
					(size 1.27 1.27)
				)
				(hide yes)
			)
		)
		(property "Manufacturer" "Panasonic"
			(at 331.47 45.72 0)
			(effects
				(font
					(size 1.27 1.27)
					(thickness 0.15)
				)
				(justify left bottom)
				(hide yes)
			)
		)
		(property "MPN" "ERJ2GE0R00X"
			(at 328.93 45.72 0)
			(effects
				(font
					(size 1.27 1.27)
					(thickness 0.15)
				)
				(justify left bottom)
				(hide yes)
			)
		)
		(property "Val" "0R"
			(at 311.15 64.7699 90)
			(effects
				(font
					(size 1.27 1.27)
					(thickness 0.15)
				)
				(justify right)
			)
		)
		(property "License" "Apache-2.0"
			(at 334.01 45.72 0)
			(effects
				(font
					(size 1.27 1.27)
					(thickness 0.15)
				)
				(justify left bottom)
				(hide yes)
			)
		)
		(property "Author" "Antmicro"
			(at 336.55 45.72 0)
			(effects
				(font
					(size 1.27 1.27)
					(thickness 0.15)
				)
				(justify left bottom)
				(hide yes)
			)
		)
		(property "Tolerance" "~"
			(at 318.77 45.72 0)
			(effects
				(font
					(size 1.27 1.27)
				)
				(justify left bottom)
				(hide yes)
			)
		)
		(property "Current" "1A"
			(at 311.15 66.0399 90)
			(effects
				(font
					(size 1.27 1.27)
					(thickness 0.15)
				)
				(justify right)
				(hide yes)
			)
		)
		(pin "1"
		)
		(pin "2"
		)
		(instances
			(project "data-center-rdimm-ddr5-tester"
				(path ""
					(reference "R155")
					(unit 1)
				)
			)
		)
	)
	(symbol
		(lib_id "antmicroCapacitorsmisc:C_22u_25V_0805")
		(at 128.27 58.42 90)
		(unit 1)
		(exclude_from_sim no)
		(in_bom yes)
		(on_board yes)
		(dnp no)
		(property "Reference" "C173"
			(at 128.905 53.975 90)
			(effects
				(font
					(size 1.27 1.27)
				)
				(justify right)
			)
		)
		(property "Value" "C_22u_25V_0805"
			(at 132.08 58.42 0)
			(effects
				(font
					(size 1.27 1.27)
				)
				(hide yes)
			)
		)
		(property "Footprint" "antmicro-footprints:C_0805_2012Metric"
			(at 123.19 53.34 0)
			(effects
				(font
					(size 1.27 1.27)
				)
				(justify left)
				(hide yes)
			)
		)
		(property "Datasheet" "https://product.samsungsem.com/mlcc/CL21A226MAYNNN.do"
			(at 128.27 58.42 0)
			(effects
				(font
					(size 1.27 1.27)
				)
				(hide yes)
			)
		)
		(property "Description" ""
			(at 128.27 58.42 0)
			(effects
				(font
					(size 1.27 1.27)
				)
				(hide yes)
			)
		)
		(property "Manufacturer" "Samsung Electro-Mechanics"
			(at 118.11 53.34 0)
			(effects
				(font
					(size 1.27 1.27)
				)
				(justify left)
				(hide yes)
			)
		)
		(property "MPN" "CL21A226MAYNNNE"
			(at 120.65 53.34 0)
			(effects
				(font
					(size 1.27 1.27)
				)
				(justify left)
				(hide yes)
			)
		)
		(property "Val" "22u"
			(at 128.905 57.785 90)
			(effects
				(font
					(size 1.27 1.27)
				)
				(justify right)
			)
		)
		(property "License" "Apache-2.0"
			(at 151.13 38.1 0)
			(effects
				(font
					(size 1.27 1.27)
					(thickness 0.15)
				)
				(justify left bottom)
				(hide yes)
			)
		)
		(property "Author" "Antmicro"
			(at 153.67 38.1 0)
			(effects
				(font
					(size 1.27 1.27)
					(thickness 0.15)
				)
				(justify left bottom)
				(hide yes)
			)
		)
		(property "Voltage" "25V"
			(at 156.21 38.1 0)
			(effects
				(font
					(size 1.27 1.27)
				)
				(justify left bottom)
				(hide yes)
			)
		)
		(property "Dielectric" "X5R"
			(at 158.75 38.1 0)
			(effects
				(font
					(size 1.27 1.27)
				)
				(justify left bottom)
				(hide yes)
			)
		)
		(property "Public" "False"
			(at 161.29 38.1 0)
			(effects
				(font
					(size 1.27 1.27)
				)
				(justify left bottom)
				(hide yes)
			)
		)
		(pin "1"
		)
		(pin "2"
		)
		(instances
			(project "data-center-rdimm-ddr5-tester"
				(path ""
					(reference "C173")
					(unit 1)
				)
			)
		)
	)
	(symbol
		(lib_id "antmicroResistorsmisc:R_0R01_1206")
		(at 223.52 110.49 0)
		(unit 1)
		(exclude_from_sim no)
		(in_bom yes)
		(on_board yes)
		(dnp no)
		(property "Reference" "R148"
			(at 226.06 105.41 0)
			(effects
				(font
					(size 1.27 1.27)
				)
			)
		)
		(property "Value" "R_0R01_1206"
			(at 243.84 123.19 0)
			(effects
				(font
					(size 1.27 1.27)
					(thickness 0.15)
				)
				(justify left bottom)
				(hide yes)
			)
		)
		(property "Footprint" "antmicro-footprints:R_1206_3216Metric"
			(at 243.84 125.73 0)
			(effects
				(font
					(size 1.27 1.27)
					(thickness 0.15)
				)
				(justify left bottom)
				(hide yes)
			)
		)
		(property "Datasheet" "https://www.yageo.com/upload/media/product/productsearch/datasheet/rchip/PYu-RL_Group_521_RoHS_L_2.pdf"
			(at 243.84 128.27 0)
			(effects
				(font
					(size 1.27 1.27)
					(thickness 0.15)
				)
				(justify left bottom)
				(hide yes)
			)
		)
		(property "Description" ""
			(at 223.52 110.49 0)
			(effects
				(font
					(size 1.27 1.27)
				)
				(hide yes)
			)
		)
		(property "Manufacturer" "YAGEO"
			(at 243.84 133.35 0)
			(effects
				(font
					(size 1.27 1.27)
					(thickness 0.15)
				)
				(justify left bottom)
				(hide yes)
			)
		)
		(property "MPN" "RL1206FR-7W0R01L"
			(at 243.84 130.81 0)
			(effects
				(font
					(size 1.27 1.27)
					(thickness 0.15)
				)
				(justify left bottom)
				(hide yes)
			)
		)
		(property "Val" "0R01"
			(at 226.06 107.95 0)
			(effects
				(font
					(size 1.27 1.27)
					(thickness 0.15)
				)
			)
		)
		(property "License" "Apache-2.0"
			(at 243.84 135.89 0)
			(effects
				(font
					(size 1.27 1.27)
					(thickness 0.15)
				)
				(justify left bottom)
				(hide yes)
			)
		)
		(property "Author" "Antmicro"
			(at 243.84 138.43 0)
			(effects
				(font
					(size 1.27 1.27)
					(thickness 0.15)
				)
				(justify left bottom)
				(hide yes)
			)
		)
		(property "Tolerance" "1%"
			(at 243.84 120.65 0)
			(effects
				(font
					(size 1.27 1.27)
				)
				(justify left bottom)
				(hide yes)
			)
		)
		(pin "1"
		)
		(pin "2"
		)
		(instances
			(project "data-center-rdimm-ddr5-tester"
				(path ""
					(reference "R148")
					(unit 1)
				)
			)
		)
	)
	(symbol
		(lib_id "antmicroShuntsJumpers:Net-Tie_P0.127mm")
		(at 222.25 97.79 90)
		(unit 1)
		(exclude_from_sim no)
		(in_bom no)
		(on_board yes)
		(dnp no)
		(fields_autoplaced yes)
		(property "Reference" "NT7"
			(at 220.98 97.79 0)
			(effects
				(font
					(size 1.27 1.27)
				)
				(hide yes)
			)
		)
		(property "Value" "Net-Tie_P0.127mm"
			(at 229.87 76.2 0)
			(effects
				(font
					(size 1.27 1.27)
					(thickness 0.15)
				)
				(justify left bottom)
				(hide yes)
			)
		)
		(property "Footprint" "antmicro-footprints:NetTie-2_SMD_Pad0.127mm"
			(at 234.95 76.2 0)
			(effects
				(font
					(size 1.27 1.27)
					(thickness 0.15)
				)
				(justify left bottom)
				(hide yes)
			)
		)
		(property "Datasheet" ""
			(at 237.49 76.2 0)
			(effects
				(font
					(size 1.27 1.27)
					(thickness 0.15)
				)
				(justify left bottom)
				(hide yes)
			)
		)
		(property "Description" ""
			(at 222.25 97.79 0)
			(effects
				(font
					(size 1.27 1.27)
				)
				(hide yes)
			)
		)
		(property "MPN" ""
			(at 232.41 76.2 0)
			(effects
				(font
					(size 1.27 1.27)
					(thickness 0.15)
				)
				(justify left bottom)
			)
		)
		(property "Manufacturer" ""
			(at 240.03 76.2 0)
			(effects
				(font
					(size 1.27 1.27)
					(thickness 0.15)
				)
				(justify left bottom)
				(hide yes)
			)
		)
		(property "Author" "Antmicro"
			(at 242.57 76.2 0)
			(effects
				(font
					(size 1.27 1.27)
					(thickness 0.15)
				)
				(justify left bottom)
				(hide yes)
			)
		)
		(property "License" "Apache-2.0"
			(at 245.11 76.2 0)
			(effects
				(font
					(size 1.27 1.27)
					(thickness 0.15)
				)
				(justify left bottom)
				(hide yes)
			)
		)
		(pin "1"
		)
		(pin "2"
		)
		(instances
			(project "data-center-rdimm-ddr5-tester"
				(path ""
					(reference "NT7")
					(unit 1)
				)
			)
		)
	)
	(symbol
		(lib_id "antmicropower:GND")
		(at 128.27 60.96 0)
		(unit 1)
		(exclude_from_sim no)
		(in_bom yes)
		(on_board yes)
		(dnp no)
		(property "Reference" "#PWR0290"
			(at 128.27 67.31 0)
			(effects
				(font
					(size 1.27 1.27)
				)
				(hide yes)
			)
		)
		(property "Value" "GND"
			(at 126.365 65.405 0)
			(effects
				(font
					(size 1.27 1.27)
					(thickness 0.15)
				)
				(justify left bottom)
			)
		)
		(property "Footprint" ""
			(at 137.16 68.58 0)
			(effects
				(font
					(size 1.27 1.27)
					(thickness 0.15)
				)
				(justify left bottom)
				(hide yes)
			)
		)
		(property "Datasheet" ""
			(at 137.16 73.66 0)
			(effects
				(font
					(size 1.27 1.27)
					(thickness 0.15)
				)
				(justify left bottom)
				(hide yes)
			)
		)
		(property "Description" ""
			(at 128.27 60.96 0)
			(effects
				(font
					(size 1.27 1.27)
				)
				(hide yes)
			)
		)
		(property "Author" "Antmicro"
			(at 137.16 66.04 0)
			(effects
				(font
					(size 1.27 1.27)
					(thickness 0.15)
				)
				(justify left bottom)
				(hide yes)
			)
		)
		(property "License" "Apache-2.0"
			(at 137.16 68.58 0)
			(effects
				(font
					(size 1.27 1.27)
					(thickness 0.15)
				)
				(justify left bottom)
				(hide yes)
			)
		)
		(pin "1"
		)
		(instances
			(project "data-center-rdimm-ddr5-tester"
				(path ""
					(reference "#PWR0290")
					(unit 1)
				)
			)
		)
	)
	(symbol
		(lib_id "antmicroCapacitorsmisc:C_22u_25V_0805")
		(at 138.43 58.42 90)
		(unit 1)
		(exclude_from_sim no)
		(in_bom yes)
		(on_board yes)
		(dnp no)
		(property "Reference" "C178"
			(at 139.065 53.975 90)
			(effects
				(font
					(size 1.27 1.27)
				)
				(justify right)
			)
		)
		(property "Value" "C_22u_25V_0805"
			(at 142.24 58.42 0)
			(effects
				(font
					(size 1.27 1.27)
				)
				(hide yes)
			)
		)
		(property "Footprint" "antmicro-footprints:C_0805_2012Metric"
			(at 133.35 53.34 0)
			(effects
				(font
					(size 1.27 1.27)
				)
				(justify left)
				(hide yes)
			)
		)
		(property "Datasheet" "https://product.samsungsem.com/mlcc/CL21A226MAYNNN.do"
			(at 138.43 58.42 0)
			(effects
				(font
					(size 1.27 1.27)
				)
				(hide yes)
			)
		)
		(property "Description" ""
			(at 138.43 58.42 0)
			(effects
				(font
					(size 1.27 1.27)
				)
				(hide yes)
			)
		)
		(property "Manufacturer" "Samsung Electro-Mechanics"
			(at 128.27 53.34 0)
			(effects
				(font
					(size 1.27 1.27)
				)
				(justify left)
				(hide yes)
			)
		)
		(property "MPN" "CL21A226MAYNNNE"
			(at 130.81 53.34 0)
			(effects
				(font
					(size 1.27 1.27)
				)
				(justify left)
				(hide yes)
			)
		)
		(property "Val" "22u"
			(at 139.065 57.785 90)
			(effects
				(font
					(size 1.27 1.27)
				)
				(justify right)
			)
		)
		(property "License" "Apache-2.0"
			(at 161.29 38.1 0)
			(effects
				(font
					(size 1.27 1.27)
					(thickness 0.15)
				)
				(justify left bottom)
				(hide yes)
			)
		)
		(property "Author" "Antmicro"
			(at 163.83 38.1 0)
			(effects
				(font
					(size 1.27 1.27)
					(thickness 0.15)
				)
				(justify left bottom)
				(hide yes)
			)
		)
		(property "Voltage" "25V"
			(at 166.37 38.1 0)
			(effects
				(font
					(size 1.27 1.27)
				)
				(justify left bottom)
				(hide yes)
			)
		)
		(property "Dielectric" "X5R"
			(at 168.91 38.1 0)
			(effects
				(font
					(size 1.27 1.27)
				)
				(justify left bottom)
				(hide yes)
			)
		)
		(property "Public" "False"
			(at 171.45 38.1 0)
			(effects
				(font
					(size 1.27 1.27)
				)
				(justify left bottom)
				(hide yes)
			)
		)
		(pin "1"
		)
		(pin "2"
		)
		(instances
			(project "data-center-rdimm-ddr5-tester"
				(path ""
					(reference "C178")
					(unit 1)
				)
			)
		)
	)
	(symbol
		(lib_id "antmicropower:GND")
		(at 148.59 105.41 0)
		(unit 1)
		(exclude_from_sim no)
		(in_bom yes)
		(on_board yes)
		(dnp no)
		(fields_autoplaced yes)
		(property "Reference" "#PWR0296"
			(at 148.59 111.76 0)
			(effects
				(font
					(size 1.27 1.27)
				)
				(hide yes)
			)
		)
		(property "Value" "GND"
			(at 146.685 109.855 0)
			(effects
				(font
					(size 1.27 1.27)
					(thickness 0.15)
				)
				(justify left bottom)
			)
		)
		(property "Footprint" ""
			(at 157.48 113.03 0)
			(effects
				(font
					(size 1.27 1.27)
					(thickness 0.15)
				)
				(justify left bottom)
				(hide yes)
			)
		)
		(property "Datasheet" ""
			(at 157.48 118.11 0)
			(effects
				(font
					(size 1.27 1.27)
					(thickness 0.15)
				)
				(justify left bottom)
				(hide yes)
			)
		)
		(property "Description" ""
			(at 148.59 105.41 0)
			(effects
				(font
					(size 1.27 1.27)
				)
				(hide yes)
			)
		)
		(property "Author" "Antmicro"
			(at 157.48 110.49 0)
			(effects
				(font
					(size 1.27 1.27)
					(thickness 0.15)
				)
				(justify left bottom)
				(hide yes)
			)
		)
		(property "License" "Apache-2.0"
			(at 157.48 113.03 0)
			(effects
				(font
					(size 1.27 1.27)
					(thickness 0.15)
				)
				(justify left bottom)
				(hide yes)
			)
		)
		(pin "1"
		)
		(instances
			(project "data-center-rdimm-ddr5-tester"
				(path ""
					(reference "#PWR0296")
					(unit 1)
				)
			)
		)
	)
	(symbol
		(lib_id "antmicropower:+5V")
		(at 251.46 72.39 0)
		(unit 1)
		(exclude_from_sim no)
		(in_bom yes)
		(on_board yes)
		(dnp no)
		(fields_autoplaced yes)
		(property "Reference" "#PWR0326"
			(at 251.46 76.2 0)
			(effects
				(font
					(size 1.27 1.27)
				)
				(hide yes)
			)
		)
		(property "Value" "+5V"
			(at 251.46 68.8156 0)
			(effects
				(font
					(size 1.27 1.27)
					(thickness 0.15)
				)
			)
		)
		(property "Footprint" ""
			(at 266.7 80.01 0)
			(effects
				(font
					(size 1.27 1.27)
					(thickness 0.15)
				)
				(justify left bottom)
				(hide yes)
			)
		)
		(property "Datasheet" ""
			(at 266.7 82.55 0)
			(effects
				(font
					(size 1.27 1.27)
					(thickness 0.15)
				)
				(justify left bottom)
				(hide yes)
			)
		)
		(property "Description" ""
			(at 251.46 72.39 0)
			(effects
				(font
					(size 1.27 1.27)
				)
				(hide yes)
			)
		)
		(property "Author" "Antmicro"
			(at 266.7 80.01 0)
			(effects
				(font
					(size 1.27 1.27)
					(thickness 0.15)
				)
				(justify left bottom)
				(hide yes)
			)
		)
		(property "License" "Apache-2.0"
			(at 266.7 82.55 0)
			(effects
				(font
					(size 1.27 1.27)
					(thickness 0.15)
				)
				(justify left bottom)
				(hide yes)
			)
		)
		(pin "1"
		)
		(instances
			(project "data-center-rdimm-ddr5-tester"
				(path ""
					(reference "#PWR0326")
					(unit 1)
				)
			)
		)
	)
	(symbol
		(lib_id "antmicroResistorsmisc:R_0R01_1206")
		(at 223.52 52.07 0)
		(unit 1)
		(exclude_from_sim no)
		(in_bom yes)
		(on_board yes)
		(dnp no)
		(property "Reference" "R145"
			(at 226.06 46.99 0)
			(effects
				(font
					(size 1.27 1.27)
				)
			)
		)
		(property "Value" "R_0R01_1206"
			(at 243.84 64.77 0)
			(effects
				(font
					(size 1.27 1.27)
					(thickness 0.15)
				)
				(justify left bottom)
				(hide yes)
			)
		)
		(property "Footprint" "antmicro-footprints:R_1206_3216Metric"
			(at 243.84 67.31 0)
			(effects
				(font
					(size 1.27 1.27)
					(thickness 0.15)
				)
				(justify left bottom)
				(hide yes)
			)
		)
		(property "Datasheet" "https://www.yageo.com/upload/media/product/productsearch/datasheet/rchip/PYu-RL_Group_521_RoHS_L_2.pdf"
			(at 243.84 69.85 0)
			(effects
				(font
					(size 1.27 1.27)
					(thickness 0.15)
				)
				(justify left bottom)
				(hide yes)
			)
		)
		(property "Description" ""
			(at 223.52 52.07 0)
			(effects
				(font
					(size 1.27 1.27)
				)
				(hide yes)
			)
		)
		(property "Manufacturer" "YAGEO"
			(at 243.84 74.93 0)
			(effects
				(font
					(size 1.27 1.27)
					(thickness 0.15)
				)
				(justify left bottom)
				(hide yes)
			)
		)
		(property "MPN" "RL1206FR-7W0R01L"
			(at 243.84 72.39 0)
			(effects
				(font
					(size 1.27 1.27)
					(thickness 0.15)
				)
				(justify left bottom)
				(hide yes)
			)
		)
		(property "Val" "0R01"
			(at 226.06 49.53 0)
			(effects
				(font
					(size 1.27 1.27)
					(thickness 0.15)
				)
			)
		)
		(property "License" "Apache-2.0"
			(at 243.84 77.47 0)
			(effects
				(font
					(size 1.27 1.27)
					(thickness 0.15)
				)
				(justify left bottom)
				(hide yes)
			)
		)
		(property "Author" "Antmicro"
			(at 243.84 80.01 0)
			(effects
				(font
					(size 1.27 1.27)
					(thickness 0.15)
				)
				(justify left bottom)
				(hide yes)
			)
		)
		(property "Tolerance" "1%"
			(at 243.84 62.23 0)
			(effects
				(font
					(size 1.27 1.27)
				)
				(justify left bottom)
				(hide yes)
			)
		)
		(pin "1"
		)
		(pin "2"
		)
		(instances
			(project "data-center-rdimm-ddr5-tester"
				(path ""
					(reference "R145")
					(unit 1)
				)
			)
		)
	)
	(symbol
		(lib_id "antmicroShuntsJumpers:Net-Tie_P0.127mm")
		(at 229.87 80.01 90)
		(unit 1)
		(exclude_from_sim no)
		(in_bom no)
		(on_board yes)
		(dnp no)
		(fields_autoplaced yes)
		(property "Reference" "NT14"
			(at 228.6 80.01 0)
			(effects
				(font
					(size 1.27 1.27)
				)
				(hide yes)
			)
		)
		(property "Value" "Net-Tie_P0.127mm"
			(at 237.49 58.42 0)
			(effects
				(font
					(size 1.27 1.27)
					(thickness 0.15)
				)
				(justify left bottom)
				(hide yes)
			)
		)
		(property "Footprint" "antmicro-footprints:NetTie-2_SMD_Pad0.127mm"
			(at 242.57 58.42 0)
			(effects
				(font
					(size 1.27 1.27)
					(thickness 0.15)
				)
				(justify left bottom)
				(hide yes)
			)
		)
		(property "Datasheet" ""
			(at 245.11 58.42 0)
			(effects
				(font
					(size 1.27 1.27)
					(thickness 0.15)
				)
				(justify left bottom)
				(hide yes)
			)
		)
		(property "Description" ""
			(at 229.87 80.01 0)
			(effects
				(font
					(size 1.27 1.27)
				)
				(hide yes)
			)
		)
		(property "MPN" ""
			(at 240.03 58.42 0)
			(effects
				(font
					(size 1.27 1.27)
					(thickness 0.15)
				)
				(justify left bottom)
			)
		)
		(property "Manufacturer" ""
			(at 247.65 58.42 0)
			(effects
				(font
					(size 1.27 1.27)
					(thickness 0.15)
				)
				(justify left bottom)
				(hide yes)
			)
		)
		(property "Author" "Antmicro"
			(at 250.19 58.42 0)
			(effects
				(font
					(size 1.27 1.27)
					(thickness 0.15)
				)
				(justify left bottom)
				(hide yes)
			)
		)
		(property "License" "Apache-2.0"
			(at 252.73 58.42 0)
			(effects
				(font
					(size 1.27 1.27)
					(thickness 0.15)
				)
				(justify left bottom)
				(hide yes)
			)
		)
		(pin "1"
		)
		(pin "2"
		)
		(instances
			(project "data-center-rdimm-ddr5-tester"
				(path ""
					(reference "NT14")
					(unit 1)
				)
			)
		)
	)
	(symbol
		(lib_id "antmicroCapacitors0402:C_100n_0402")
		(at 104.14 207.01 270)
		(unit 1)
		(exclude_from_sim no)
		(in_bom yes)
		(on_board yes)
		(dnp no)
		(fields_autoplaced yes)
		(property "Reference" "C206"
			(at 101.6 208.2863 90)
			(effects
				(font
					(size 1.27 1.27)
				)
				(justify right)
			)
		)
		(property "Value" "C_100n_0402"
			(at 93.98 227.33 0)
			(effects
				(font
					(size 1.27 1.27)
					(thickness 0.15)
				)
				(justify left bottom)
				(hide yes)
			)
		)
		(property "Footprint" "antmicro-footprints:C_0402_1005Metric"
			(at 91.44 227.33 0)
			(effects
				(font
					(size 1.27 1.27)
					(thickness 0.15)
				)
				(justify left bottom)
				(hide yes)
			)
		)
		(property "Datasheet" "https://www.murata.com/products/productdetail?partno=GRM155R61H104KE14%23"
			(at 88.9 227.33 0)
			(effects
				(font
					(size 1.27 1.27)
					(thickness 0.15)
				)
				(justify left bottom)
				(hide yes)
			)
		)
		(property "Description" ""
			(at 104.14 207.01 0)
			(effects
				(font
					(size 1.27 1.27)
				)
				(hide yes)
			)
		)
		(property "Manufacturer" "Murata"
			(at 83.82 227.33 0)
			(effects
				(font
					(size 1.27 1.27)
					(thickness 0.15)
				)
				(justify left bottom)
				(hide yes)
			)
		)
		(property "MPN" "GRM155R61H104KE14D"
			(at 86.36 227.33 0)
			(effects
				(font
					(size 1.27 1.27)
					(thickness 0.15)
				)
				(justify left bottom)
				(hide yes)
			)
		)
		(property "Val" "100n"
			(at 101.6 211.4612 90)
			(effects
				(font
					(size 1.27 1.27)
					(thickness 0.15)
				)
				(justify right)
			)
		)
		(property "License" "Apache-2.0"
			(at 81.28 227.33 0)
			(effects
				(font
					(size 1.27 1.27)
					(thickness 0.15)
				)
				(justify left bottom)
				(hide yes)
			)
		)
		(property "Author" "Antmicro"
			(at 78.74 227.33 0)
			(effects
				(font
					(size 1.27 1.27)
					(thickness 0.15)
				)
				(justify left bottom)
				(hide yes)
			)
		)
		(property "Voltage" "50V"
			(at 76.2 227.33 0)
			(effects
				(font
					(size 1.27 1.27)
				)
				(justify left bottom)
				(hide yes)
			)
		)
		(property "Dielectric" "X5R"
			(at 73.66 227.33 0)
			(effects
				(font
					(size 1.27 1.27)
				)
				(justify left bottom)
				(hide yes)
			)
		)
		(pin "1"
		)
		(pin "2"
		)
		(instances
			(project "data-center-rdimm-ddr5-tester"
				(path ""
					(reference "C206")
					(unit 1)
				)
			)
		)
	)
	(symbol
		(lib_id "antmicroResistors0402:R_0R_0402")
		(at 309.88 111.76 90)
		(unit 1)
		(exclude_from_sim no)
		(in_bom no)
		(on_board yes)
		(dnp yes)
		(property "Reference" "R158"
			(at 312.42 107.95 90)
			(effects
				(font
					(size 1.27 1.27)
				)
				(justify right)
			)
		)
		(property "Value" "R_0R_0402"
			(at 322.58 91.44 0)
			(effects
				(font
					(size 1.27 1.27)
					(thickness 0.15)
				)
				(justify left bottom)
				(hide yes)
			)
		)
		(property "Footprint" "antmicro-footprints:R_0402_1005Metric"
			(at 325.12 91.44 0)
			(effects
				(font
					(size 1.27 1.27)
					(thickness 0.15)
				)
				(justify left bottom)
				(hide yes)
			)
		)
		(property "Datasheet" "https://industrial.panasonic.com/cdbs/www-data/pdf/RDA0000/AOA0000C301.pdf"
			(at 327.66 91.44 0)
			(effects
				(font
					(size 1.27 1.27)
					(thickness 0.15)
				)
				(justify left bottom)
				(hide yes)
			)
		)
		(property "Description" ""
			(at 309.88 111.76 0)
			(effects
				(font
					(size 1.27 1.27)
				)
				(hide yes)
			)
		)
		(property "Manufacturer" "Panasonic"
			(at 332.74 91.44 0)
			(effects
				(font
					(size 1.27 1.27)
					(thickness 0.15)
				)
				(justify left bottom)
				(hide yes)
			)
		)
		(property "MPN" "ERJ2GE0R00X"
			(at 330.2 91.44 0)
			(effects
				(font
					(size 1.27 1.27)
					(thickness 0.15)
				)
				(justify left bottom)
				(hide yes)
			)
		)
		(property "Val" "0R"
			(at 312.42 110.49 90)
			(effects
				(font
					(size 1.27 1.27)
					(thickness 0.15)
				)
				(justify right)
			)
		)
		(property "License" "Apache-2.0"
			(at 335.28 91.44 0)
			(effects
				(font
					(size 1.27 1.27)
					(thickness 0.15)
				)
				(justify left bottom)
				(hide yes)
			)
		)
		(property "Author" "Antmicro"
			(at 337.82 91.44 0)
			(effects
				(font
					(size 1.27 1.27)
					(thickness 0.15)
				)
				(justify left bottom)
				(hide yes)
			)
		)
		(property "Tolerance" "~"
			(at 320.04 91.44 0)
			(effects
				(font
					(size 1.27 1.27)
				)
				(justify left bottom)
				(hide yes)
			)
		)
		(property "Current" "1A"
			(at 312.42 113.0299 90)
			(effects
				(font
					(size 1.27 1.27)
					(thickness 0.15)
				)
				(justify right)
				(hide yes)
			)
		)
		(pin "1"
		)
		(pin "2"
		)
		(instances
			(project "data-center-rdimm-ddr5-tester"
				(path ""
					(reference "R158")
					(unit 1)
				)
			)
		)
	)
	(symbol
		(lib_id "antmicroCapacitors0402:C_1u_0402")
		(at 128.27 78.74 90)
		(unit 1)
		(exclude_from_sim no)
		(in_bom yes)
		(on_board yes)
		(dnp no)
		(fields_autoplaced yes)
		(property "Reference" "C174"
			(at 130.81 74.9235 90)
			(effects
				(font
					(size 1.27 1.27)
				)
				(justify right)
			)
		)
		(property "Value" "C_1u_0402"
			(at 132.08 78.74 0)
			(effects
				(font
					(size 1.27 1.27)
				)
				(hide yes)
			)
		)
		(property "Footprint" "antmicro-footprints:C_0402_1005Metric"
			(at 123.19 73.66 0)
			(effects
				(font
					(size 1.27 1.27)
				)
				(justify left)
				(hide yes)
			)
		)
		(property "Datasheet" "https://product.tdk.com/en/search/capacitor/ceramic/mlcc/info?part_no=C1005X6S1A105K050BC"
			(at 128.27 78.74 0)
			(effects
				(font
					(size 1.27 1.27)
				)
				(hide yes)
			)
		)
		(property "Description" ""
			(at 128.27 78.74 0)
			(effects
				(font
					(size 1.27 1.27)
				)
				(hide yes)
			)
		)
		(property "Manufacturer" "TDK"
			(at 118.11 73.66 0)
			(effects
				(font
					(size 1.27 1.27)
				)
				(justify left)
				(hide yes)
			)
		)
		(property "MPN" "C1005X6S1A105K050BC"
			(at 120.65 73.66 0)
			(effects
				(font
					(size 1.27 1.27)
				)
				(justify left)
				(hide yes)
			)
		)
		(property "Val" "1u"
			(at 130.81 77.4635 90)
			(effects
				(font
					(size 1.27 1.27)
				)
				(justify right)
			)
		)
		(property "License" "Apache-2.0"
			(at 151.13 58.42 0)
			(effects
				(font
					(size 1.27 1.27)
					(thickness 0.15)
				)
				(justify left bottom)
				(hide yes)
			)
		)
		(property "Author" "Antmicro"
			(at 153.67 58.42 0)
			(effects
				(font
					(size 1.27 1.27)
					(thickness 0.15)
				)
				(justify left bottom)
				(hide yes)
			)
		)
		(property "Voltage" ""
			(at 156.21 58.42 0)
			(effects
				(font
					(size 1.27 1.27)
				)
				(justify left bottom)
				(hide yes)
			)
		)
		(property "Dielectric" ""
			(at 158.75 58.42 0)
			(effects
				(font
					(size 1.27 1.27)
				)
				(justify left bottom)
				(hide yes)
			)
		)
		(pin "1"
		)
		(pin "2"
		)
		(instances
			(project "data-center-rdimm-ddr5-tester"
				(path ""
					(reference "C174")
					(unit 1)
				)
			)
		)
	)
	(symbol
		(lib_id "antmicropower:PWR_FLAG")
		(at 241.3 72.39 0)
		(unit 1)
		(exclude_from_sim no)
		(in_bom yes)
		(on_board yes)
		(dnp no)
		(fields_autoplaced yes)
		(property "Reference" "#FLG013"
			(at 241.3 70.485 0)
			(effects
				(font
					(size 1.27 1.27)
				)
				(hide yes)
			)
		)
		(property "Value" "PWR_FLAG"
			(at 241.3 68.8142 0)
			(effects
				(font
					(size 1.27 1.27)
				)
			)
		)
		(property "Footprint" ""
			(at 241.3 72.39 0)
			(effects
				(font
					(size 1.27 1.27)
				)
				(hide yes)
			)
		)
		(property "Datasheet" ""
			(at 241.3 72.39 0)
			(effects
				(font
					(size 1.27 1.27)
				)
				(hide yes)
			)
		)
		(property "Description" ""
			(at 241.3 72.39 0)
			(effects
				(font
					(size 1.27 1.27)
				)
				(hide yes)
			)
		)
		(pin "1"
		)
		(instances
			(project "data-center-rdimm-ddr5-tester"
				(path ""
					(reference "#FLG013")
					(unit 1)
				)
			)
		)
	)
	(symbol
		(lib_id "antmicropower:GND")
		(at 308.61 80.01 0)
		(unit 1)
		(exclude_from_sim no)
		(in_bom yes)
		(on_board yes)
		(dnp no)
		(fields_autoplaced yes)
		(property "Reference" "#PWR0337"
			(at 308.61 86.36 0)
			(effects
				(font
					(size 1.27 1.27)
				)
				(hide yes)
			)
		)
		(property "Value" "GND"
			(at 306.705 84.455 0)
			(effects
				(font
					(size 1.27 1.27)
					(thickness 0.15)
				)
				(justify left bottom)
			)
		)
		(property "Footprint" ""
			(at 317.5 87.63 0)
			(effects
				(font
					(size 1.27 1.27)
					(thickness 0.15)
				)
				(justify left bottom)
				(hide yes)
			)
		)
		(property "Datasheet" ""
			(at 317.5 92.71 0)
			(effects
				(font
					(size 1.27 1.27)
					(thickness 0.15)
				)
				(justify left bottom)
				(hide yes)
			)
		)
		(property "Description" ""
			(at 308.61 80.01 0)
			(effects
				(font
					(size 1.27 1.27)
				)
				(hide yes)
			)
		)
		(property "Author" "Antmicro"
			(at 317.5 85.09 0)
			(effects
				(font
					(size 1.27 1.27)
					(thickness 0.15)
				)
				(justify left bottom)
				(hide yes)
			)
		)
		(property "License" "Apache-2.0"
			(at 317.5 87.63 0)
			(effects
				(font
					(size 1.27 1.27)
					(thickness 0.15)
				)
				(justify left bottom)
				(hide yes)
			)
		)
		(pin "1"
		)
		(instances
			(project "data-center-rdimm-ddr5-tester"
				(path ""
					(reference "#PWR0337")
					(unit 1)
				)
			)
		)
	)
	(symbol
		(lib_id "antmicroPowerMeasurement:PAC1944T-E")
		(at 148.59 210.82 0)
		(unit 1)
		(exclude_from_sim no)
		(in_bom yes)
		(on_board yes)
		(dnp no)
		(fields_autoplaced yes)
		(property "Reference" "U28"
			(at 161.29 203.2 0)
			(effects
				(font
					(size 1.27 1.27)
					(thickness 0.15)
				)
			)
		)
		(property "Value" "PAC1944T-E"
			(at 186.69 218.44 0)
			(effects
				(font
					(size 1.27 1.27)
					(thickness 0.15)
				)
				(justify left bottom)
				(hide yes)
			)
		)
		(property "Footprint" "antmicro-footprints:VQFN-16-1EP_3x3mm_P0.5mm_EP1.1x1.1mm"
			(at 186.69 220.98 0)
			(effects
				(font
					(size 1.27 1.27)
					(thickness 0.15)
				)
				(justify left bottom)
				(hide yes)
			)
		)
		(property "Datasheet" "https://ww1.microchip.com/downloads/aemDocuments/documents/MSLD/ProductDocuments/DataSheets/PAC194X-Family-Data-Sheet-DS20006543.pdf"
			(at 186.69 223.52 0)
			(effects
				(font
					(size 1.27 1.27)
					(thickness 0.15)
				)
				(justify left bottom)
				(hide yes)
			)
		)
		(property "Description" ""
			(at 148.59 210.82 0)
			(effects
				(font
					(size 1.27 1.27)
				)
				(hide yes)
			)
		)
		(property "MPN" "PAC1944T-E/4MX"
			(at 161.29 205.74 0)
			(effects
				(font
					(size 1.27 1.27)
					(thickness 0.15)
				)
			)
		)
		(property "Manufacturer" "Microchip Technology"
			(at 186.69 226.06 0)
			(effects
				(font
					(size 1.27 1.27)
					(thickness 0.15)
				)
				(justify left bottom)
				(hide yes)
			)
		)
		(property "Author" "Antmicro"
			(at 186.69 228.6 0)
			(effects
				(font
					(size 1.27 1.27)
					(thickness 0.15)
				)
				(justify left bottom)
				(hide yes)
			)
		)
		(property "License" "Apache-2.0"
			(at 186.69 231.14 0)
			(effects
				(font
					(size 1.27 1.27)
					(thickness 0.15)
				)
				(justify left bottom)
				(hide yes)
			)
		)
		(pin "7"
		)
		(pin "8"
		)
		(pin "11"
		)
		(pin "10"
		)
		(pin "6"
		)
		(pin "15"
		)
		(pin "17"
		)
		(pin "13"
		)
		(pin "14"
		)
		(pin "9"
		)
		(pin "3"
		)
		(pin "2"
		)
		(pin "1"
		)
		(pin "12"
		)
		(pin "4"
		)
		(pin "5"
		)
		(pin "16"
		)
		(instances
			(project "data-center-rdimm-ddr5-tester"
				(path ""
					(reference "U28")
					(unit 1)
				)
			)
		)
	)
	(symbol
		(lib_id "antmicroResistors0402:R_0R_0402")
		(at 339.09 101.6 90)
		(unit 1)
		(exclude_from_sim no)
		(in_bom yes)
		(on_board yes)
		(dnp no)
		(fields_autoplaced yes)
		(property "Reference" "R168"
			(at 340.995 97.7899 90)
			(effects
				(font
					(size 1.27 1.27)
				)
				(justify right)
			)
		)
		(property "Value" "R_0R_0402"
			(at 351.79 81.28 0)
			(effects
				(font
					(size 1.27 1.27)
					(thickness 0.15)
				)
				(justify left bottom)
				(hide yes)
			)
		)
		(property "Footprint" "antmicro-footprints:R_0402_1005Metric"
			(at 354.33 81.28 0)
			(effects
				(font
					(size 1.27 1.27)
					(thickness 0.15)
				)
				(justify left bottom)
				(hide yes)
			)
		)
		(property "Datasheet" "https://industrial.panasonic.com/cdbs/www-data/pdf/RDA0000/AOA0000C301.pdf"
			(at 356.87 81.28 0)
			(effects
				(font
					(size 1.27 1.27)
					(thickness 0.15)
				)
				(justify left bottom)
				(hide yes)
			)
		)
		(property "Description" ""
			(at 339.09 101.6 0)
			(effects
				(font
					(size 1.27 1.27)
				)
				(hide yes)
			)
		)
		(property "Manufacturer" "Panasonic"
			(at 361.95 81.28 0)
			(effects
				(font
					(size 1.27 1.27)
					(thickness 0.15)
				)
				(justify left bottom)
				(hide yes)
			)
		)
		(property "MPN" "ERJ2GE0R00X"
			(at 359.41 81.28 0)
			(effects
				(font
					(size 1.27 1.27)
					(thickness 0.15)
				)
				(justify left bottom)
				(hide yes)
			)
		)
		(property "Val" "0R"
			(at 340.995 100.3299 90)
			(effects
				(font
					(size 1.27 1.27)
					(thickness 0.15)
				)
				(justify right)
			)
		)
		(property "License" "Apache-2.0"
			(at 364.49 81.28 0)
			(effects
				(font
					(size 1.27 1.27)
					(thickness 0.15)
				)
				(justify left bottom)
				(hide yes)
			)
		)
		(property "Author" "Antmicro"
			(at 367.03 81.28 0)
			(effects
				(font
					(size 1.27 1.27)
					(thickness 0.15)
				)
				(justify left bottom)
				(hide yes)
			)
		)
		(property "Tolerance" "~"
			(at 349.25 81.28 0)
			(effects
				(font
					(size 1.27 1.27)
				)
				(justify left bottom)
				(hide yes)
			)
		)
		(property "Current" "1A"
			(at 340.995 101.5999 90)
			(effects
				(font
					(size 1.27 1.27)
					(thickness 0.15)
				)
				(justify right)
				(hide yes)
			)
		)
		(pin "1"
		)
		(pin "2"
		)
		(instances
			(project "data-center-rdimm-ddr5-tester"
				(path ""
					(reference "R168")
					(unit 1)
				)
			)
		)
	)
	(symbol
		(lib_id "antmicropower:GND")
		(at 203.2 63.5 0)
		(unit 1)
		(exclude_from_sim no)
		(in_bom yes)
		(on_board yes)
		(dnp no)
		(fields_autoplaced yes)
		(property "Reference" "#PWR0308"
			(at 203.2 69.85 0)
			(effects
				(font
					(size 1.27 1.27)
				)
				(hide yes)
			)
		)
		(property "Value" "GND"
			(at 201.295 67.945 0)
			(effects
				(font
					(size 1.27 1.27)
					(thickness 0.15)
				)
				(justify left bottom)
			)
		)
		(property "Footprint" ""
			(at 212.09 71.12 0)
			(effects
				(font
					(size 1.27 1.27)
					(thickness 0.15)
				)
				(justify left bottom)
				(hide yes)
			)
		)
		(property "Datasheet" ""
			(at 212.09 76.2 0)
			(effects
				(font
					(size 1.27 1.27)
					(thickness 0.15)
				)
				(justify left bottom)
				(hide yes)
			)
		)
		(property "Description" ""
			(at 203.2 63.5 0)
			(effects
				(font
					(size 1.27 1.27)
				)
				(hide yes)
			)
		)
		(property "Author" "Antmicro"
			(at 212.09 68.58 0)
			(effects
				(font
					(size 1.27 1.27)
					(thickness 0.15)
				)
				(justify left bottom)
				(hide yes)
			)
		)
		(property "License" "Apache-2.0"
			(at 212.09 71.12 0)
			(effects
				(font
					(size 1.27 1.27)
					(thickness 0.15)
				)
				(justify left bottom)
				(hide yes)
			)
		)
		(pin "1"
		)
		(instances
			(project "data-center-rdimm-ddr5-tester"
				(path ""
					(reference "#PWR0308")
					(unit 1)
				)
			)
		)
	)
	(symbol
		(lib_id "antmicropower:VDC")
		(at 128.27 49.53 0)
		(unit 1)
		(exclude_from_sim no)
		(in_bom yes)
		(on_board yes)
		(dnp no)
		(fields_autoplaced yes)
		(property "Reference" "#PWR0289"
			(at 128.27 52.07 0)
			(effects
				(font
					(size 1.27 1.27)
				)
				(hide yes)
			)
		)
		(property "Value" "VDC"
			(at 128.27 44.45 0)
			(effects
				(font
					(size 1.27 1.27)
				)
			)
		)
		(property "Footprint" ""
			(at 128.27 49.53 0)
			(effects
				(font
					(size 1.27 1.27)
				)
				(hide yes)
			)
		)
		(property "Datasheet" ""
			(at 128.27 49.53 0)
			(effects
				(font
					(size 1.27 1.27)
				)
				(hide yes)
			)
		)
		(property "Description" ""
			(at 128.27 49.53 0)
			(effects
				(font
					(size 1.27 1.27)
				)
				(hide yes)
			)
		)
		(pin "1"
		)
		(instances
			(project "data-center-rdimm-ddr5-tester"
				(path ""
					(reference "#PWR0289")
					(unit 1)
				)
			)
		)
	)
	(symbol
		(lib_id "antmicropower:GND")
		(at 128.27 81.28 0)
		(unit 1)
		(exclude_from_sim no)
		(in_bom yes)
		(on_board yes)
		(dnp no)
		(fields_autoplaced yes)
		(property "Reference" "#PWR0291"
			(at 128.27 87.63 0)
			(effects
				(font
					(size 1.27 1.27)
				)
				(hide yes)
			)
		)
		(property "Value" "GND"
			(at 126.365 85.725 0)
			(effects
				(font
					(size 1.27 1.27)
					(thickness 0.15)
				)
				(justify left bottom)
			)
		)
		(property "Footprint" ""
			(at 137.16 88.9 0)
			(effects
				(font
					(size 1.27 1.27)
					(thickness 0.15)
				)
				(justify left bottom)
				(hide yes)
			)
		)
		(property "Datasheet" ""
			(at 137.16 93.98 0)
			(effects
				(font
					(size 1.27 1.27)
					(thickness 0.15)
				)
				(justify left bottom)
				(hide yes)
			)
		)
		(property "Description" ""
			(at 128.27 81.28 0)
			(effects
				(font
					(size 1.27 1.27)
				)
				(hide yes)
			)
		)
		(property "Author" "Antmicro"
			(at 137.16 86.36 0)
			(effects
				(font
					(size 1.27 1.27)
					(thickness 0.15)
				)
				(justify left bottom)
				(hide yes)
			)
		)
		(property "License" "Apache-2.0"
			(at 137.16 88.9 0)
			(effects
				(font
					(size 1.27 1.27)
					(thickness 0.15)
				)
				(justify left bottom)
				(hide yes)
			)
		)
		(pin "1"
		)
		(instances
			(project "data-center-rdimm-ddr5-tester"
				(path ""
					(reference "#PWR0291")
					(unit 1)
				)
			)
		)
	)
	(symbol
		(lib_id "antmicroCapacitors0603:C_22u_0603")
		(at 203.2 116.84 90)
		(unit 1)
		(exclude_from_sim no)
		(in_bom yes)
		(on_board yes)
		(dnp no)
		(fields_autoplaced yes)
		(property "Reference" "C193"
			(at 200.8759 112.1971 90)
			(effects
				(font
					(size 1.27 1.27)
				)
				(justify left)
			)
		)
		(property "Value" "C_22u_0603"
			(at 213.36 96.52 0)
			(effects
				(font
					(size 1.27 1.27)
					(thickness 0.15)
				)
				(justify left bottom)
				(hide yes)
			)
		)
		(property "Footprint" "antmicro-footprints:C_0603_1608Metric"
			(at 215.9 96.52 0)
			(effects
				(font
					(size 1.27 1.27)
					(thickness 0.15)
				)
				(justify left bottom)
				(hide yes)
			)
		)
		(property "Datasheet" "https://www.murata.com/products/productdetail?partno=GRM188R60J226MEA0%23"
			(at 218.44 96.52 0)
			(effects
				(font
					(size 1.27 1.27)
					(thickness 0.15)
				)
				(justify left bottom)
				(hide yes)
			)
		)
		(property "Description" ""
			(at 203.2 116.84 0)
			(effects
				(font
					(size 1.27 1.27)
				)
				(hide yes)
			)
		)
		(property "Manufacturer" "Murata"
			(at 223.52 96.52 0)
			(effects
				(font
					(size 1.27 1.27)
					(thickness 0.15)
				)
				(justify left bottom)
				(hide yes)
			)
		)
		(property "MPN" "GRM188R60J226MEA0D"
			(at 220.98 96.52 0)
			(effects
				(font
					(size 1.27 1.27)
					(thickness 0.15)
				)
				(justify left bottom)
				(hide yes)
			)
		)
		(property "Val" "22u"
			(at 200.8759 114.7274 90)
			(effects
				(font
					(size 1.27 1.27)
					(thickness 0.15)
				)
				(justify left)
			)
		)
		(property "License" "Apache-2.0"
			(at 226.06 96.52 0)
			(effects
				(font
					(size 1.27 1.27)
					(thickness 0.15)
				)
				(justify left bottom)
				(hide yes)
			)
		)
		(property "Author" "Antmicro"
			(at 228.6 96.52 0)
			(effects
				(font
					(size 1.27 1.27)
					(thickness 0.15)
				)
				(justify left bottom)
				(hide yes)
			)
		)
		(property "Voltage" ""
			(at 231.14 96.52 0)
			(effects
				(font
					(size 1.27 1.27)
				)
				(justify left bottom)
				(hide yes)
			)
		)
		(property "Dielectric" ""
			(at 233.68 96.52 0)
			(effects
				(font
					(size 1.27 1.27)
				)
				(justify left bottom)
				(hide yes)
			)
		)
		(pin "1"
		)
		(pin "2"
		)
		(instances
			(project "data-center-rdimm-ddr5-tester"
				(path ""
					(reference "C193")
					(unit 1)
				)
			)
		)
	)
	(symbol
		(lib_id "antmicropower:+3V3")
		(at 250.19 49.53 0)
		(unit 1)
		(exclude_from_sim no)
		(in_bom yes)
		(on_board yes)
		(dnp no)
		(property "Reference" "#PWR0322"
			(at 250.19 53.34 0)
			(effects
				(font
					(size 1.27 1.27)
				)
				(hide yes)
			)
		)
		(property "Value" "+3V3"
			(at 247.015 46.99 0)
			(effects
				(font
					(size 1.27 1.27)
					(thickness 0.15)
				)
				(justify left bottom)
			)
		)
		(property "Footprint" ""
			(at 265.43 57.15 0)
			(effects
				(font
					(size 1.27 1.27)
					(thickness 0.15)
				)
				(justify left bottom)
				(hide yes)
			)
		)
		(property "Datasheet" ""
			(at 265.43 59.69 0)
			(effects
				(font
					(size 1.27 1.27)
					(thickness 0.15)
				)
				(justify left bottom)
				(hide yes)
			)
		)
		(property "Description" ""
			(at 250.19 49.53 0)
			(effects
				(font
					(size 1.27 1.27)
				)
				(hide yes)
			)
		)
		(property "Author" "Antmicro"
			(at 265.43 52.07 0)
			(effects
				(font
					(size 1.27 1.27)
					(thickness 0.15)
				)
				(justify left bottom)
				(hide yes)
			)
		)
		(property "License" "Apache-2.0"
			(at 265.43 54.61 0)
			(effects
				(font
					(size 1.27 1.27)
					(thickness 0.15)
				)
				(justify left bottom)
				(hide yes)
			)
		)
		(pin "1"
		)
		(instances
			(project "data-center-rdimm-ddr5-tester"
				(path ""
					(reference "#PWR0322")
					(unit 1)
				)
			)
		)
	)
	(symbol
		(lib_id "antmicroShuntsJumpers:Net-Tie_P0.127mm")
		(at 229.87 58.42 90)
		(unit 1)
		(exclude_from_sim no)
		(in_bom no)
		(on_board yes)
		(dnp no)
		(fields_autoplaced yes)
		(property "Reference" "NT13"
			(at 228.6 58.42 0)
			(effects
				(font
					(size 1.27 1.27)
				)
				(hide yes)
			)
		)
		(property "Value" "Net-Tie_P0.127mm"
			(at 237.49 36.83 0)
			(effects
				(font
					(size 1.27 1.27)
					(thickness 0.15)
				)
				(justify left bottom)
				(hide yes)
			)
		)
		(property "Footprint" "antmicro-footprints:NetTie-2_SMD_Pad0.127mm"
			(at 242.57 36.83 0)
			(effects
				(font
					(size 1.27 1.27)
					(thickness 0.15)
				)
				(justify left bottom)
				(hide yes)
			)
		)
		(property "Datasheet" ""
			(at 245.11 36.83 0)
			(effects
				(font
					(size 1.27 1.27)
					(thickness 0.15)
				)
				(justify left bottom)
				(hide yes)
			)
		)
		(property "Description" ""
			(at 229.87 58.42 0)
			(effects
				(font
					(size 1.27 1.27)
				)
				(hide yes)
			)
		)
		(property "MPN" ""
			(at 240.03 36.83 0)
			(effects
				(font
					(size 1.27 1.27)
					(thickness 0.15)
				)
				(justify left bottom)
			)
		)
		(property "Manufacturer" ""
			(at 247.65 36.83 0)
			(effects
				(font
					(size 1.27 1.27)
					(thickness 0.15)
				)
				(justify left bottom)
				(hide yes)
			)
		)
		(property "Author" "Antmicro"
			(at 250.19 36.83 0)
			(effects
				(font
					(size 1.27 1.27)
					(thickness 0.15)
				)
				(justify left bottom)
				(hide yes)
			)
		)
		(property "License" "Apache-2.0"
			(at 252.73 36.83 0)
			(effects
				(font
					(size 1.27 1.27)
					(thickness 0.15)
				)
				(justify left bottom)
				(hide yes)
			)
		)
		(pin "1"
		)
		(pin "2"
		)
		(instances
			(project "data-center-rdimm-ddr5-tester"
				(path ""
					(reference "NT13")
					(unit 1)
				)
			)
		)
	)
	(symbol
		(lib_id "antmicropower:GND")
		(at 104.14 213.36 0)
		(unit 1)
		(exclude_from_sim no)
		(in_bom yes)
		(on_board yes)
		(dnp no)
		(fields_autoplaced yes)
		(property "Reference" "#PWR0390"
			(at 104.14 219.71 0)
			(effects
				(font
					(size 1.27 1.27)
				)
				(hide yes)
			)
		)
		(property "Value" "GND"
			(at 102.235 217.805 0)
			(effects
				(font
					(size 1.27 1.27)
					(thickness 0.15)
				)
				(justify left bottom)
			)
		)
		(property "Footprint" ""
			(at 113.03 220.98 0)
			(effects
				(font
					(size 1.27 1.27)
					(thickness 0.15)
				)
				(justify left bottom)
				(hide yes)
			)
		)
		(property "Datasheet" ""
			(at 113.03 226.06 0)
			(effects
				(font
					(size 1.27 1.27)
					(thickness 0.15)
				)
				(justify left bottom)
				(hide yes)
			)
		)
		(property "Description" ""
			(at 104.14 213.36 0)
			(effects
				(font
					(size 1.27 1.27)
				)
				(hide yes)
			)
		)
		(property "Author" "Antmicro"
			(at 113.03 218.44 0)
			(effects
				(font
					(size 1.27 1.27)
					(thickness 0.15)
				)
				(justify left bottom)
				(hide yes)
			)
		)
		(property "License" "Apache-2.0"
			(at 113.03 220.98 0)
			(effects
				(font
					(size 1.27 1.27)
					(thickness 0.15)
				)
				(justify left bottom)
				(hide yes)
			)
		)
		(pin "1"
		)
		(instances
			(project "data-center-rdimm-ddr5-tester"
				(path ""
					(reference "#PWR0390")
					(unit 1)
				)
			)
		)
	)
	(symbol
		(lib_id "antmicroTestPoints:TP_1mm_SMD")
		(at 251.46 110.49 0)
		(unit 1)
		(exclude_from_sim no)
		(in_bom no)
		(on_board yes)
		(dnp no)
		(fields_autoplaced yes)
		(property "Reference" "TP11"
			(at 256.032 110.9238 0)
			(effects
				(font
					(size 1.27 1.27)
				)
				(justify left)
			)
		)
		(property "Value" "TP_1mm_SMD"
			(at 266.7 118.11 0)
			(effects
				(font
					(size 1.27 1.27)
					(thickness 0.15)
				)
				(justify left bottom)
				(hide yes)
			)
		)
		(property "Footprint" "antmicro-footprints:TP_SMD_1mm"
			(at 266.7 120.65 0)
			(effects
				(font
					(size 1.27 1.27)
					(thickness 0.15)
				)
				(justify left bottom)
				(hide yes)
			)
		)
		(property "Datasheet" ""
			(at 266.7 123.19 0)
			(effects
				(font
					(size 1.27 1.27)
					(thickness 0.15)
				)
				(justify left bottom)
				(hide yes)
			)
		)
		(property "Description" ""
			(at 251.46 110.49 0)
			(effects
				(font
					(size 1.27 1.27)
				)
				(hide yes)
			)
		)
		(property "MPN" ""
			(at 251.46 110.49 0)
			(effects
				(font
					(size 1.27 1.27)
				)
				(hide yes)
			)
		)
		(property "Manufacturer" ""
			(at 251.46 110.49 0)
			(effects
				(font
					(size 1.27 1.27)
				)
				(hide yes)
			)
		)
		(property "Author" "Antmicro"
			(at 266.7 125.73 0)
			(effects
				(font
					(size 1.27 1.27)
					(thickness 0.15)
				)
				(justify left bottom)
				(hide yes)
			)
		)
		(property "License" "Apache-2.0"
			(at 266.7 128.27 0)
			(effects
				(font
					(size 1.27 1.27)
					(thickness 0.15)
				)
				(justify left bottom)
				(hide yes)
			)
		)
		(pin "1"
		)
		(instances
			(project "data-center-rdimm-ddr5-tester"
				(path ""
					(reference "TP11")
					(unit 1)
				)
			)
		)
	)
)
